G04 ================== begin FILE IDENTIFICATION RECORD ==================*
G04 Layout Name:  13130-1b.brd*
G04 Film Name:    L2GND*
G04 File Format:  Gerber RS274X*
G04 File Origin:  Cadence Allegro 16.5-S037*
G04 Origin Date:  Thu Nov 13 17:26:50 2014*
G04 *
G04 Layer:  VIA CLASS/L2GND*
G04 Layer:  PIN/L2GND*
G04 Layer:  ETCH/L2GND*
G04 Layer:  DRAWING FORMAT/LAYER_PCB_STORY*
G04 Layer:  DRAWING FORMAT/LAYER_L2GND*
G04 *
G04 Offset:    (0.00 0.00)*
G04 Mirror:    No*
G04 Mode:      Negative*
G04 Rotation:  0*
G04 FullContactRelief:  No*
G04 UndefLineWidth:     6.00*
G04 ================== end FILE IDENTIFICATION RECORD ====================*
%FSLAX35Y35*MOIN*%
%IR0*IPPOS*OFA0.00000B0.00000*MIA0B0*SFA1.00000B1.00000*%
%ADD15C,.03*%
%ADD20C,.032*%
%ADD18C,.072*%
%ADD13C,.036*%
%ADD24C,.028*%
%ADD22C,.091*%
%ADD17C,.093*%
%ADD19C,.068*%
%AMMACRO23*
4,1,15,.00398,.00044,
.003999,.000208,
.004004,-.000025,
.003996,-.000258,
.00398,-.00044,
.00483,-.00129,
.004897,-.001007,
.004947,-.000721,
.004981,-.000432,
.004997,-.000141,
.004997,.000149,
.00498,.00044,
.004946,.000729,
.004895,.001015,
.00483,.00129,
.00398,.00044,
45.*
4,1,15,.00044,-.00398,
.000208,-.003999,
-.000025,-.004004,
-.000258,-.003996,
-.00044,-.00398,
-.00129,-.00483,
-.001007,-.004897,
-.000721,-.004947,
-.000432,-.004981,
-.000141,-.004997,
.000149,-.004997,
.00044,-.00498,
.000729,-.004946,
.001015,-.004895,
.00129,-.00483,
.00044,-.00398,
45.*
4,1,15,-.00398,-.00044,
-.003999,-.000208,
-.004004,.000025,
-.003996,.000258,
-.00398,.00044,
-.00483,.00129,
-.004897,.001007,
-.004947,.000721,
-.004981,.000432,
-.004997,.000141,
-.004997,-.000149,
-.00498,-.00044,
-.004946,-.000729,
-.004895,-.001015,
-.00483,-.00129,
-.00398,-.00044,
45.*
4,1,15,-.00044,.00398,
-.000208,.003999,
.000025,.004004,
.000258,.003996,
.00044,.00398,
.00129,.00483,
.001007,.004897,
.000721,.004947,
.000432,.004981,
.000141,.004997,
-.000149,.004997,
-.00044,.00498,
-.000729,.004946,
-.001015,.004895,
-.00129,.00483,
-.00044,.00398,
45.*
%
%ADD23MACRO23*%
%AMMACRO14*
4,1,15,.00398,.00044,
.003999,.000208,
.004004,-.000025,
.003996,-.000258,
.00398,-.00044,
.00483,-.00129,
.004897,-.001007,
.004947,-.000721,
.004981,-.000432,
.004997,-.000141,
.004997,.000149,
.00498,.00044,
.004946,.000729,
.004895,.001015,
.00483,.00129,
.00398,.00044,
90.*
4,1,15,.00044,-.00398,
.000208,-.003999,
-.000025,-.004004,
-.000258,-.003996,
-.00044,-.00398,
-.00129,-.00483,
-.001007,-.004897,
-.000721,-.004947,
-.000432,-.004981,
-.000141,-.004997,
.000149,-.004997,
.00044,-.00498,
.000729,-.004946,
.001015,-.004895,
.00129,-.00483,
.00044,-.00398,
90.*
4,1,15,-.00398,-.00044,
-.003999,-.000208,
-.004004,.000025,
-.003996,.000258,
-.00398,.00044,
-.00483,.00129,
-.004897,.001007,
-.004947,.000721,
-.004981,.000432,
-.004997,.000141,
-.004997,-.000149,
-.00498,-.00044,
-.004946,-.000729,
-.004895,-.001015,
-.00483,-.00129,
-.00398,-.00044,
90.*
4,1,15,-.00044,.00398,
-.000208,.003999,
.000025,.004004,
.000258,.003996,
.00044,.00398,
.00129,.00483,
.001007,.004897,
.000721,.004947,
.000432,.004981,
.000141,.004997,
-.000149,.004997,
-.00044,.00498,
-.000729,.004946,
-.001015,.004895,
-.00129,.00483,
-.00044,.00398,
90.*
%
%ADD14MACRO14*%
%AMMACRO12*
4,1,15,.00398,.00044,
.003999,.000208,
.004004,-.000025,
.003996,-.000258,
.00398,-.00044,
.00483,-.00129,
.004897,-.001007,
.004947,-.000721,
.004981,-.000432,
.004997,-.000141,
.004997,.000149,
.00498,.00044,
.004946,.000729,
.004895,.001015,
.00483,.00129,
.00398,.00044,
0.0*
4,1,15,.00044,-.00398,
.000208,-.003999,
-.000025,-.004004,
-.000258,-.003996,
-.00044,-.00398,
-.00129,-.00483,
-.001007,-.004897,
-.000721,-.004947,
-.000432,-.004981,
-.000141,-.004997,
.000149,-.004997,
.00044,-.00498,
.000729,-.004946,
.001015,-.004895,
.00129,-.00483,
.00044,-.00398,
0.0*
4,1,15,-.00398,-.00044,
-.003999,-.000208,
-.004004,.000025,
-.003996,.000258,
-.00398,.00044,
-.00483,.00129,
-.004897,.001007,
-.004947,.000721,
-.004981,.000432,
-.004997,.000141,
-.004997,-.000149,
-.00498,-.00044,
-.004946,-.000729,
-.004895,-.001015,
-.00483,-.00129,
-.00398,-.00044,
0.0*
4,1,15,-.00044,.00398,
-.000208,.003999,
.000025,.004004,
.000258,.003996,
.00044,.00398,
.00129,.00483,
.001007,.004897,
.000721,.004947,
.000432,.004981,
.000141,.004997,
-.000149,.004997,
-.00044,.00498,
-.000729,.004946,
-.001015,.004895,
-.00129,.00483,
-.00044,.00398,
0.0*
%
%ADD12MACRO12*%
%AMMACRO31*
4,1,14,.02782,.01368,
.029773,.008641,
.030821,.00334,
.030933,-.002063,
.030105,-.007403,
.028362,-.012518,
.02782,-.01368,
.03153,-.01738,
.034069,-.011641,
.035573,-.005548,
.035996,.000713,
.035325,.006953,
.033581,.012982,
.03153,.01738,
.02782,.01368,
270.*
4,1,14,.01368,-.02782,
.008641,-.029773,
.00334,-.030821,
-.002063,-.030933,
-.007403,-.030105,
-.012518,-.028362,
-.01368,-.02782,
-.01738,-.03153,
-.011641,-.034069,
-.005548,-.035573,
.000713,-.035996,
.006953,-.035325,
.012982,-.033581,
.01738,-.03153,
.01368,-.02782,
270.*
4,1,14,-.02782,-.01368,
-.029773,-.008641,
-.030821,-.00334,
-.030933,.002063,
-.030105,.007403,
-.028362,.012518,
-.02782,.01368,
-.03153,.01738,
-.034069,.011641,
-.035573,.005548,
-.035996,-.000713,
-.035325,-.006953,
-.033581,-.012982,
-.03153,-.01738,
-.02782,-.01368,
270.*
4,1,14,-.01368,.02782,
-.008641,.029773,
-.00334,.030821,
.002063,.030933,
.007403,.030105,
.012518,.028362,
.01368,.02782,
.01738,.03153,
.011641,.034069,
.005548,.035573,
-.000713,.035996,
-.006953,.035325,
-.012982,.033581,
-.01738,.03153,
-.01368,.02782,
270.*
%
%ADD31MACRO31*%
%ADD29O,.217X.154*%
%ADD11C,.114*%
%ADD16C,.154*%
%ADD21C,.147*%
%ADD10C,.168*%
%AMMACRO30*
4,1,15,.00398,.00044,
.003999,.000208,
.004004,-.000025,
.003996,-.000258,
.00398,-.00044,
.00483,-.00129,
.004897,-.001007,
.004947,-.000721,
.004981,-.000432,
.004997,-.000141,
.004997,.000149,
.00498,.00044,
.004946,.000729,
.004895,.001015,
.00483,.00129,
.00398,.00044,
225.*
4,1,15,.00044,-.00398,
.000208,-.003999,
-.000025,-.004004,
-.000258,-.003996,
-.00044,-.00398,
-.00129,-.00483,
-.001007,-.004897,
-.000721,-.004947,
-.000432,-.004981,
-.000141,-.004997,
.000149,-.004997,
.00044,-.00498,
.000729,-.004946,
.001015,-.004895,
.00129,-.00483,
.00044,-.00398,
225.*
4,1,15,-.00398,-.00044,
-.003999,-.000208,
-.004004,.000025,
-.003996,.000258,
-.00398,.00044,
-.00483,.00129,
-.004897,.001007,
-.004947,.000721,
-.004981,.000432,
-.004997,.000141,
-.004997,-.000149,
-.00498,-.00044,
-.004946,-.000729,
-.004895,-.001015,
-.00483,-.00129,
-.00398,-.00044,
225.*
4,1,15,-.00044,.00398,
-.000208,.003999,
.000025,.004004,
.000258,.003996,
.00044,.00398,
.00129,.00483,
.001007,.004897,
.000721,.004947,
.000432,.004981,
.000141,.004997,
-.000149,.004997,
-.00044,.00498,
-.000729,.004946,
-.001015,.004895,
-.00129,.00483,
-.00044,.00398,
225.*
%
%ADD30MACRO30*%
%AMMACRO28*
4,1,15,.00398,.00044,
.003999,.000208,
.004004,-.000025,
.003996,-.000258,
.00398,-.00044,
.00483,-.00129,
.004897,-.001007,
.004947,-.000721,
.004981,-.000432,
.004997,-.000141,
.004997,.000149,
.00498,.00044,
.004946,.000729,
.004895,.001015,
.00483,.00129,
.00398,.00044,
315.*
4,1,15,.00044,-.00398,
.000208,-.003999,
-.000025,-.004004,
-.000258,-.003996,
-.00044,-.00398,
-.00129,-.00483,
-.001007,-.004897,
-.000721,-.004947,
-.000432,-.004981,
-.000141,-.004997,
.000149,-.004997,
.00044,-.00498,
.000729,-.004946,
.001015,-.004895,
.00129,-.00483,
.00044,-.00398,
315.*
4,1,15,-.00398,-.00044,
-.003999,-.000208,
-.004004,.000025,
-.003996,.000258,
-.00398,.00044,
-.00483,.00129,
-.004897,.001007,
-.004947,.000721,
-.004981,.000432,
-.004997,.000141,
-.004997,-.000149,
-.00498,-.00044,
-.004946,-.000729,
-.004895,-.001015,
-.00483,-.00129,
-.00398,-.00044,
315.*
4,1,15,-.00044,.00398,
-.000208,.003999,
.000025,.004004,
.000258,.003996,
.00044,.00398,
.00129,.00483,
.001007,.004897,
.000721,.004947,
.000432,.004981,
.000141,.004997,
-.000149,.004997,
-.00044,.00498,
-.000729,.004946,
-.001015,.004895,
-.00129,.00483,
-.00044,.00398,
315.*
%
%ADD28MACRO28*%
%AMMACRO27*
4,1,15,.00398,.00044,
.003999,.000208,
.004004,-.000025,
.003996,-.000258,
.00398,-.00044,
.00483,-.00129,
.004897,-.001007,
.004947,-.000721,
.004981,-.000432,
.004997,-.000141,
.004997,.000149,
.00498,.00044,
.004946,.000729,
.004895,.001015,
.00483,.00129,
.00398,.00044,
180.*
4,1,15,.00044,-.00398,
.000208,-.003999,
-.000025,-.004004,
-.000258,-.003996,
-.00044,-.00398,
-.00129,-.00483,
-.001007,-.004897,
-.000721,-.004947,
-.000432,-.004981,
-.000141,-.004997,
.000149,-.004997,
.00044,-.00498,
.000729,-.004946,
.001015,-.004895,
.00129,-.00483,
.00044,-.00398,
180.*
4,1,15,-.00398,-.00044,
-.003999,-.000208,
-.004004,.000025,
-.003996,.000258,
-.00398,.00044,
-.00483,.00129,
-.004897,.001007,
-.004947,.000721,
-.004981,.000432,
-.004997,.000141,
-.004997,-.000149,
-.00498,-.00044,
-.004946,-.000729,
-.004895,-.001015,
-.00483,-.00129,
-.00398,-.00044,
180.*
4,1,15,-.00044,.00398,
-.000208,.003999,
.000025,.004004,
.000258,.003996,
.00044,.00398,
.00129,.00483,
.001007,.004897,
.000721,.004947,
.000432,.004981,
.000141,.004997,
-.000149,.004997,
-.00044,.00498,
-.000729,.004946,
-.001015,.004895,
-.00129,.00483,
-.00044,.00398,
180.*
%
%ADD27MACRO27*%
%AMMACRO26*
4,1,15,.00398,.00044,
.003999,.000208,
.004004,-.000025,
.003996,-.000258,
.00398,-.00044,
.00483,-.00129,
.004897,-.001007,
.004947,-.000721,
.004981,-.000432,
.004997,-.000141,
.004997,.000149,
.00498,.00044,
.004946,.000729,
.004895,.001015,
.00483,.00129,
.00398,.00044,
270.*
4,1,15,.00044,-.00398,
.000208,-.003999,
-.000025,-.004004,
-.000258,-.003996,
-.00044,-.00398,
-.00129,-.00483,
-.001007,-.004897,
-.000721,-.004947,
-.000432,-.004981,
-.000141,-.004997,
.000149,-.004997,
.00044,-.00498,
.000729,-.004946,
.001015,-.004895,
.00129,-.00483,
.00044,-.00398,
270.*
4,1,15,-.00398,-.00044,
-.003999,-.000208,
-.004004,.000025,
-.003996,.000258,
-.00398,.00044,
-.00483,.00129,
-.004897,.001007,
-.004947,.000721,
-.004981,.000432,
-.004997,.000141,
-.004997,-.000149,
-.00498,-.00044,
-.004946,-.000729,
-.004895,-.001015,
-.00483,-.00129,
-.00398,-.00044,
270.*
4,1,15,-.00044,.00398,
-.000208,.003999,
.000025,.004004,
.000258,.003996,
.00044,.00398,
.00129,.00483,
.001007,.004897,
.000721,.004947,
.000432,.004981,
.000141,.004997,
-.000149,.004997,
-.00044,.00498,
-.000729,.004946,
-.001015,.004895,
-.00129,.00483,
-.00044,.00398,
270.*
%
%ADD26MACRO26*%
%AMMACRO25*
4,1,15,.00398,.00044,
.003999,.000208,
.004004,-.000025,
.003996,-.000258,
.00398,-.00044,
.00483,-.00129,
.004897,-.001007,
.004947,-.000721,
.004981,-.000432,
.004997,-.000141,
.004997,.000149,
.00498,.00044,
.004946,.000729,
.004895,.001015,
.00483,.00129,
.00398,.00044,
135.*
4,1,15,.00044,-.00398,
.000208,-.003999,
-.000025,-.004004,
-.000258,-.003996,
-.00044,-.00398,
-.00129,-.00483,
-.001007,-.004897,
-.000721,-.004947,
-.000432,-.004981,
-.000141,-.004997,
.000149,-.004997,
.00044,-.00498,
.000729,-.004946,
.001015,-.004895,
.00129,-.00483,
.00044,-.00398,
135.*
4,1,15,-.00398,-.00044,
-.003999,-.000208,
-.004004,.000025,
-.003996,.000258,
-.00398,.00044,
-.00483,.00129,
-.004897,.001007,
-.004947,.000721,
-.004981,.000432,
-.004997,.000141,
-.004997,-.000149,
-.00498,-.00044,
-.004946,-.000729,
-.004895,-.001015,
-.00483,-.00129,
-.00398,-.00044,
135.*
4,1,15,-.00044,.00398,
-.000208,.003999,
.000025,.004004,
.000258,.003996,
.00044,.00398,
.00129,.00483,
.001007,.004897,
.000721,.004947,
.000432,.004981,
.000141,.004997,
-.000149,.004997,
-.00044,.00498,
-.000729,.004946,
-.001015,.004895,
-.00129,.00483,
-.00044,.00398,
135.*
%
%ADD25MACRO25*%
%ADD32C,.02*%
%ADD33C,.006*%
%ADD41C,.03004*%
%ADD39C,.06404*%
%ADD38C,.06804*%
%ADD40C,.08704*%
%ADD37C,.08904*%
%ADD34O,.21302X.15002*%
%ADD35C,.11004*%
%ADD36C,.15004*%
G75*
%LPD*%
G75*
G36*
G01X-6000Y-6000D02*
X832773D01*
Y296551D01*
X-6000D01*
Y-6000D01*
G37*
%LPC*%
G75*
G36*
G01X3937Y60878D02*
G02X3004Y61811I0J933D01*
G01Y286614D01*
G02X3937Y287547I933J0D01*
G01X193177D01*
G02X193514Y286932I0J-400D01*
G03X206880I6683J-4255D01*
G02X207217Y287547I337J215D01*
G01X291579D01*
G02X291917Y286933I0J-400D01*
G03X305327I6705J-4256D01*
G02X305665Y287547I338J214D01*
G01X822835D01*
G02X823768Y286614I0J-933D01*
G01Y3937D01*
G02X822835Y3004I-933J0D01*
G01X669250D01*
Y14189D01*
X672250Y17189D01*
Y19811D01*
X670250Y21811D01*
Y39811D01*
X658811Y51250D01*
X616189D01*
X614250Y49311D01*
Y42811D01*
X612250Y40811D01*
Y3004D01*
X417323D01*
G02X416390Y3937I0J933D01*
G01Y42126D01*
G03X409449Y49067I-6941J0D01*
G01X393701D01*
G03X386760Y42126I0J-6941D01*
G01Y20648D01*
X348673D01*
Y39961D01*
G03X335185I-6744J0D01*
G01Y20648D01*
X333498D01*
Y32654D01*
X330674D01*
Y20648D01*
X329560D01*
Y32654D01*
X326738D01*
Y20648D01*
X317750D01*
Y32654D01*
X314926D01*
Y20648D01*
X313812D01*
Y32654D01*
X310990D01*
Y20648D01*
X302002D01*
Y32654D01*
X299178D01*
Y20648D01*
X298064D01*
Y32654D01*
X295242D01*
Y20648D01*
X286254D01*
Y32654D01*
X283430D01*
Y20648D01*
X282316D01*
Y32654D01*
X279494D01*
Y20648D01*
X270506D01*
Y32654D01*
X267682D01*
Y20648D01*
X266568D01*
Y32654D01*
X263746D01*
Y20648D01*
X254758D01*
Y32654D01*
X251934D01*
Y20648D01*
X250820D01*
Y32654D01*
X247998D01*
Y20648D01*
X239010D01*
Y32654D01*
X236186D01*
Y20648D01*
X235072D01*
Y32654D01*
X232250D01*
Y20648D01*
X207514D01*
Y32654D01*
X204690D01*
Y20648D01*
X203576D01*
Y32654D01*
X200754D01*
Y20648D01*
X191766D01*
Y32654D01*
X188942D01*
Y20648D01*
X187828D01*
Y32654D01*
X185006D01*
Y20648D01*
X176018D01*
Y32654D01*
X173194D01*
Y20648D01*
X172080D01*
Y32654D01*
X169258D01*
Y20648D01*
X160270D01*
Y32654D01*
X157446D01*
Y20648D01*
X156332D01*
Y32654D01*
X153510D01*
Y20648D01*
X144522D01*
Y32654D01*
X141698D01*
Y20648D01*
X140584D01*
Y32654D01*
X137762D01*
Y20648D01*
X128774D01*
Y32654D01*
X125950D01*
Y20648D01*
X124836D01*
Y32654D01*
X122014D01*
Y20648D01*
X113026D01*
Y32654D01*
X110202D01*
Y20648D01*
X109088D01*
Y32654D01*
X106266D01*
Y20648D01*
X97278D01*
Y32654D01*
X94454D01*
Y20648D01*
X93340D01*
Y32654D01*
X90518D01*
Y20648D01*
X81530D01*
Y32654D01*
X78706D01*
Y20648D01*
X77592D01*
Y32654D01*
X74770D01*
Y20648D01*
X60878D01*
Y53937D01*
G03X53937Y60878I-6941J0D01*
G01X3937D01*
G37*
G36*
G01X658189Y49750D02*
X668750Y39189D01*
Y21189D01*
X670750Y19189D01*
Y17811D01*
X667750Y14811D01*
Y3004D01*
X613750D01*
Y40189D01*
X615750Y42189D01*
Y48689D01*
X616811Y49750D01*
X658189D01*
G37*
%LPD*%
G75*
G36*
G01X9110Y260712D02*
G02X6090Y260713I-1510J1D01*
G01Y264483D01*
G02X9110I1510J0D01*
G01Y260712D01*
G37*
G36*
G01X15100Y254750D02*
G02X12080Y254751I-1510J1D01*
G01Y258521D01*
G02X15100I1510J0D01*
G01Y254750D01*
G37*
G36*
G01X39410Y253999D02*
G02X36390Y254000I-1510J1D01*
G01Y257500D01*
G02X39410I1510J0D01*
G01Y253999D01*
G37*
G36*
G01X9110Y248902D02*
G02X6090I-1510J0D01*
G01Y252673D01*
G02X9110Y252672I1510J-1D01*
G01Y248902D01*
G37*
G36*
G01X36397Y246861D02*
X36381Y247035D01*
X36481Y250542D01*
X36489Y250550D01*
X36495Y250624D01*
G02X39503Y250639I1505J-123D01*
G01X39519Y250465D01*
X39419Y246957D01*
X39394Y246785D01*
G02X36397Y246861I-1494J216D01*
G37*
G36*
G01X400528Y242794D02*
G02X398368Y244905I-1090J1045D01*
G01X400768Y247314D01*
G02X402908Y245182I1070J-1066D01*
G01X400529Y242795D01*
X400528Y242794D01*
G37*
G36*
G01X15100Y242939D02*
G02X12080Y242940I-1510J1D01*
G01Y246710D01*
G02X15100I1510J0D01*
G01Y242939D01*
G37*
G36*
G01X39410Y239999D02*
G02X36390Y240000I-1510J1D01*
G01Y243500D01*
G02X39410I1510J0D01*
G01Y239999D01*
G37*
G36*
G01X390616Y239712D02*
X390725Y239846D01*
X393170Y242218D01*
X393181D01*
X393237Y242267D01*
G02X395280Y240044I991J-1139D01*
G01X395137Y239905D01*
X395143Y239898D01*
X392844Y237667D01*
X392707Y237562D01*
G02X390616Y239712I-919J1198D01*
G37*
G36*
G01X9110Y237090D02*
G02X6090Y237091I-1510J1D01*
G01Y240861D01*
G02X9110I1510J0D01*
G01Y237090D01*
G37*
G36*
G01X36397Y232861D02*
X36381Y233035D01*
X36481Y236542D01*
X36489Y236550D01*
X36495Y236624D01*
G02X39503Y236639I1505J-123D01*
G01X39519Y236465D01*
X39419Y232957D01*
X39394Y232785D01*
G02X36397Y232861I-1494J216D01*
G37*
G36*
G01X585189Y283250D02*
X640311D01*
X641750Y281811D01*
Y246189D01*
X630811Y235250D01*
X594811D01*
X590811Y231250D01*
X582689D01*
X581250Y232689D01*
Y241311D01*
X583750Y243811D01*
Y281811D01*
X585189Y283250D01*
G37*
G36*
G01X14600Y231129D02*
G02X11580I-1510J0D01*
G01Y234900D01*
G02X14600Y234899I1510J-1D01*
G01Y231129D01*
G37*
G36*
G01X39410Y225999D02*
G02X36390Y226000I-1510J1D01*
G01Y229500D01*
G02X39410I1510J0D01*
G01Y225999D01*
G37*
G36*
G01Y218999D02*
G02X36390Y219000I-1510J1D01*
G01Y222500D01*
G02X39410I1510J0D01*
G01Y218999D01*
G37*
G36*
G01X329534Y219215D02*
G02X327485Y217426I-1025J-895D01*
G01X325999Y219130D01*
G02X328049Y220918I1025J894D01*
G01X329534Y219215D01*
G37*
G36*
G01X359255Y215107D02*
X359109Y215175D01*
X357235Y216357D01*
Y216365D01*
X357154Y216425D01*
G02X358692Y218666I812J1091D01*
G01X358861Y218559D01*
X358866Y218567D01*
X360570Y217492D01*
X360694Y217389D01*
G02X359255Y215107I-867J-1048D01*
G37*
G36*
G01X338701Y215752D02*
G02X335981Y215710I-1360J-21D01*
G01X335947Y217939D01*
G02X338667Y217982I1360J22D01*
G01X338701Y215752D01*
G37*
G36*
G01X344602Y213717D02*
G02X341882Y213663I-1360J-27D01*
G01X341838Y215882D01*
G02X344558Y215937I1360J27D01*
G01X344602Y213717D01*
G37*
G36*
G01X333018Y212687D02*
G02X330298Y212634I-1360J-26D01*
G01X330256Y214834D01*
G02X332976Y214886I1360J26D01*
G01X333018Y212687D01*
G37*
G36*
G01X354948Y210837D02*
G02X352240Y210578I-1354J-129D01*
G01X352031Y212769D01*
G02X354739Y213027I1354J129D01*
G01X354948Y210837D01*
G37*
G36*
G01X346240Y210141D02*
X346224Y210306D01*
X346295Y212525D01*
X346321Y212689D01*
G02X349017Y212612I1343J-213D01*
G01X349033Y212447D01*
X348962Y210234D01*
X348954Y210226D01*
X348947Y210154D01*
G02X346240Y210141I-1354J123D01*
G37*
G36*
G01X357162Y209968D02*
X357131Y210131D01*
X357014Y212358D01*
X357026Y212523D01*
G02X359740Y212498I1356J-97D01*
G01X359856Y210292D01*
G02X357162Y209968I-1358J-71D01*
G37*
G36*
G01X337607Y209430D02*
X337566Y211648D01*
G02X340286Y211699I1360J26D01*
G01X340327Y209480D01*
G02X337607Y209430I-1360J-25D01*
G37*
G36*
G01X53370Y187640D02*
G02X50350I-1510J0D01*
G01Y191411D01*
G02X53370Y191410I1510J-1D01*
G01Y187640D01*
G37*
G36*
G01X200951Y187570D02*
G02X197931Y187525I-1510J-23D01*
G01X197882Y190925D01*
G02X200902Y190969I1510J22D01*
G01X200951Y187570D01*
G37*
G36*
G01X59379Y185890D02*
G02Y182870I0J-1510D01*
G01X55719D01*
G02X55720Y185890I1J1510D01*
G01X59379D01*
G37*
G36*
G01X241407Y180504D02*
G02X238393Y180697I-1507J97D01*
G01X238612Y184090D01*
G02X241626Y183896I1507J-97D01*
G01X241407Y180504D01*
G37*
G36*
G01X170910Y175350D02*
G02Y172330I0J-1510D01*
G01X167139D01*
G02X167140Y175350I1J1510D01*
G01X170910D01*
G37*
G36*
G01X177194Y171390D02*
G02X177125Y174410I-35J1510D01*
G01X180897Y174495D01*
G02X180965Y171475I34J-1510D01*
G01X177194Y171390D01*
G37*
G36*
G01X195638Y148605D02*
G02X193608Y150841I-1015J1118D01*
G01X196115Y153119D01*
X196116Y153120D01*
G02X198155Y150892I1024J-1110D01*
G01X195638Y148605D01*
G37*
G36*
G01X236385Y139289D02*
G02X233365Y139290I-1510J1D01*
G01Y143060D01*
G02X236385I1510J0D01*
G01Y139289D01*
G37*
G36*
G01X210551Y140538D02*
G02X210542Y137518I-5J-1510D01*
G01X206785Y137530D01*
G02X206795Y140550I5J1510D01*
G01X210551Y140538D01*
G37*
G36*
G01X205380Y135710D02*
G02Y132690I0J-1510D01*
G01X201898D01*
G02X201899Y135710I1J1510D01*
G01X205380D01*
G37*
G36*
G01X152180Y115499D02*
G02X149160Y115500I-1510J1D01*
G01Y118900D01*
G02X152180I1510J0D01*
G01Y115499D01*
G37*
G36*
G01X210769Y113771D02*
G02X207749I-1510J0D01*
G01Y117431D01*
G02X210769Y117430I1510J-1D01*
G01Y113771D01*
G37*
G36*
G01X273710Y108360D02*
G02X270690Y108345I-1510J-7D01*
G01X270675Y111824D01*
G02X273695Y111838I1510J7D01*
G01X273710Y108360D01*
G37*
G36*
G01X197845Y81870D02*
G02Y78850I0J-1510D01*
G01X194074D01*
G02X194075Y81870I1J1510D01*
G01X197845D01*
G37*
G36*
G01X82886Y62489D02*
G02X82885Y59469I-1J-1510D01*
G01X79115D01*
G02Y62489I0J1510D01*
G01X82886D01*
G37*
G36*
G01X290200Y59410D02*
G02Y56390I0J-1510D01*
G01X286799D01*
G02X286800Y59410I1J1510D01*
G01X290200D01*
G37*
G36*
G01X271000Y59010D02*
G02Y55990I0J-1510D01*
G01X267999D01*
G02X268000Y59010I1J1510D01*
G01X271000D01*
G37*
G36*
G01X319201Y58910D02*
G02X319200Y55890I-1J-1510D01*
G01X315800D01*
G02Y58910I0J1510D01*
G01X319201D01*
G37*
G36*
G01X308200D02*
G02Y55890I0J-1510D01*
G01X304799D01*
G02X304800Y58910I1J1510D01*
G01X308200D01*
G37*
G36*
G01X135001D02*
G02X135000Y55890I-1J-1510D01*
G01X131600D01*
G02Y58910I0J1510D01*
G01X135001D01*
G37*
G36*
G01X119201D02*
G02X119200Y55890I-1J-1510D01*
G01X115800D01*
G02Y58910I0J1510D01*
G01X119201D01*
G37*
G36*
G01X327400Y56410D02*
G02Y53390I0J-1510D01*
G01X323999D01*
G02X324000Y56410I1J1510D01*
G01X327400D01*
G37*
G36*
G01X208701D02*
G02X208700Y53390I-1J-1510D01*
G01X205300D01*
G02Y56410I0J1510D01*
G01X208701D01*
G37*
G36*
G01X166464Y55910D02*
G02X166463Y52890I-1J-1510D01*
G01X163063D01*
G02Y55910I0J1510D01*
G01X166464D01*
G37*
G36*
G01X150716D02*
G02X150715Y52890I-1J-1510D01*
G01X147315D01*
G02Y55910I0J1510D01*
G01X150716D01*
G37*
G36*
G01X103451D02*
G02X103450Y52890I-1J-1510D01*
G01X100050D01*
G02Y55910I0J1510D01*
G01X103451D01*
G37*
G36*
G01X88700D02*
G02Y52890I0J-1510D01*
G01X85299D01*
G02X85300Y55910I1J1510D01*
G01X88700D01*
G37*
G36*
G01X174061Y51110D02*
G02X174060Y48090I-1J-1510D01*
G01X170290D01*
G02Y51110I0J1510D01*
G01X174061D01*
G37*
G36*
G01X159060Y50120D02*
G02Y47100I0J-1510D01*
G01X155289D01*
G02X155290Y50120I1J1510D01*
G01X159060D01*
G37*
G36*
G01X236211Y44567D02*
G02Y41547I0J-1510D01*
G01X232590D01*
G02X232591Y44567I1J1510D01*
G01X236211D01*
G37*
G36*
G01X331931Y42505D02*
G02Y39485I0J-1510D01*
G01X328302D01*
G02X328303Y42505I1J1510D01*
G01X331931D01*
G37*
G36*
G01X316254Y42200D02*
G02Y39180I0J-1510D01*
G01X312483D01*
G02X312484Y42200I1J1510D01*
G01X316254D01*
G37*
G36*
G01X300506Y42000D02*
G02Y38980I0J-1510D01*
G01X296735D01*
G02X296736Y42000I1J1510D01*
G01X300506D01*
G37*
G36*
G01X284758D02*
G02Y38980I0J-1510D01*
G01X280987D01*
G02X280988Y42000I1J1510D01*
G01X284758D01*
G37*
G36*
G01X268911D02*
G02X268910Y38980I-1J-1510D01*
G01X265140D01*
G02Y42000I0J1510D01*
G01X268911D01*
G37*
G36*
G01X198073Y41905D02*
G02Y38885I0J-1510D01*
G01X194444D01*
G02X194445Y41905I1J1510D01*
G01X198073D01*
G37*
G36*
G01X245386Y41867D02*
G02X245385Y38847I-1J-1510D01*
G01X241765D01*
G02Y41867I0J1510D01*
G01X245386D01*
G37*
G36*
G01X190267D02*
G02Y38847I0J-1510D01*
G01X186646D01*
G02X186647Y41867I1J1510D01*
G01X190267D01*
G37*
G36*
G01X174519D02*
G02Y38847I0J-1510D01*
G01X170898D01*
G02X170899Y41867I1J1510D01*
G01X174519D01*
G37*
G36*
G01X158771D02*
G02Y38847I0J-1510D01*
G01X155150D01*
G02X155151Y41867I1J1510D01*
G01X158771D01*
G37*
G36*
G01X143024D02*
G02X143023Y38847I-1J-1510D01*
G01X139403D01*
G02Y41867I0J1510D01*
G01X143024D01*
G37*
G36*
G01X127276D02*
G02X127275Y38847I-1J-1510D01*
G01X123655D01*
G02Y41867I0J1510D01*
G01X127276D01*
G37*
G36*
G01X111528D02*
G02X111527Y38847I-1J-1510D01*
G01X107907D01*
G02Y41867I0J1510D01*
G01X111528D01*
G37*
G36*
G01X95779D02*
G02Y38847I0J-1510D01*
G01X92158D01*
G02X92159Y41867I1J1510D01*
G01X95779D01*
G37*
G36*
G01X80031D02*
G02Y38847I0J-1510D01*
G01X76410D01*
G02X76411Y41867I1J1510D01*
G01X80031D01*
G37*
G36*
G01X251300Y52912D02*
G02X251512Y52700I0J-212D01*
G01Y51300D01*
G02X251300Y51088I-212J0D01*
G01X249700D01*
G02X249488Y51300I0J212D01*
G01Y52700D01*
G02X249700Y52912I212J0D01*
G01X251300D01*
G37*
G36*
G01X254300D02*
G02X254512Y52700I0J-212D01*
G01Y51300D01*
G02X254300Y51088I-212J0D01*
G01X252700D01*
G02X252488Y51300I0J212D01*
G01Y52700D01*
G02X252700Y52912I212J0D01*
G01X254300D01*
G37*
G36*
G01Y55912D02*
G02X254512Y55700I0J-212D01*
G01Y54300D01*
G02X254300Y54088I-212J0D01*
G01X252700D01*
G02X252488Y54300I0J212D01*
G01Y55700D01*
G02X252700Y55912I212J0D01*
G01X254300D01*
G37*
G36*
G01X251300D02*
G02X251512Y55700I0J-212D01*
G01Y54300D01*
G02X251300Y54088I-212J0D01*
G01X249700D01*
G02X249488Y54300I0J212D01*
G01Y55700D01*
G02X249700Y55912I212J0D01*
G01X251300D01*
G37*
G36*
G01X207800Y48088D02*
G02X207588Y48300I0J212D01*
G01Y49700D01*
G02X207800Y49912I212J0D01*
G01X209400D01*
G02X209612Y49700I0J-212D01*
G01Y48300D01*
G02X209400Y48088I-212J0D01*
G01X207800D01*
G37*
G36*
G01X204800D02*
G02X204588Y48300I0J212D01*
G01Y49700D01*
G02X204800Y49912I212J0D01*
G01X206400D01*
G02X206612Y49700I0J-212D01*
G01Y48300D01*
G02X206400Y48088I-212J0D01*
G01X204800D01*
G37*
G36*
G01X207800Y51088D02*
G02X207588Y51300I0J212D01*
G01Y52700D01*
G02X207800Y52912I212J0D01*
G01X209400D01*
G02X209612Y52700I0J-212D01*
G01Y51300D01*
G02X209400Y51088I-212J0D01*
G01X207800D01*
G37*
G36*
G01X204800D02*
G02X204588Y51300I0J212D01*
G01Y52700D01*
G02X204800Y52912I212J0D01*
G01X206400D01*
G02X206612Y52700I0J-212D01*
G01Y51300D01*
G02X206400Y51088I-212J0D01*
G01X204800D01*
G37*
G36*
G01X195500Y49412D02*
G02X195712Y49200I0J-212D01*
G01Y47800D01*
G02X195500Y47588I-212J0D01*
G01X193900D01*
G02X193688Y47800I0J212D01*
G01Y49200D01*
G02X193900Y49412I212J0D01*
G01X195500D01*
G37*
G36*
G01X198500D02*
G02X198712Y49200I0J-212D01*
G01Y47800D01*
G02X198500Y47588I-212J0D01*
G01X196900D01*
G02X196688Y47800I0J212D01*
G01Y49200D01*
G02X196900Y49412I212J0D01*
G01X198500D01*
G37*
G36*
G01Y52412D02*
G02X198712Y52200I0J-212D01*
G01Y50800D01*
G02X198500Y50588I-212J0D01*
G01X196900D01*
G02X196688Y50800I0J212D01*
G01Y52200D01*
G02X196900Y52412I212J0D01*
G01X198500D01*
G37*
G36*
G01X195500D02*
G02X195712Y52200I0J-212D01*
G01Y50800D01*
G02X195500Y50588I-212J0D01*
G01X193900D01*
G02X193688Y50800I0J212D01*
G01Y52200D01*
G02X193900Y52412I212J0D01*
G01X195500D01*
G37*
G36*
G01X48388Y208600D02*
G02X48600Y208812I212J0D01*
G01X50000D01*
G02X50212Y208600I0J-212D01*
G01Y207000D01*
G02X50000Y206788I-212J0D01*
G01X48600D01*
G02X48388Y207000I0J212D01*
G01Y208600D01*
G37*
G36*
G01Y213500D02*
G02X48600Y213712I212J0D01*
G01X50000D01*
G02X50212Y213500I0J-212D01*
G01Y211900D01*
G02X50000Y211688I-212J0D01*
G01X48600D01*
G02X48388Y211900I0J212D01*
G01Y213500D01*
G37*
G36*
G01X34088Y247800D02*
G02X34300Y248012I212J0D01*
G01X35700D01*
G02X35912Y247800I0J-212D01*
G01Y246200D01*
G02X35700Y245988I-212J0D01*
G01X34300D01*
G02X34088Y246200I0J212D01*
G01Y247800D01*
G37*
G36*
G01Y251300D02*
G02X34300Y251512I212J0D01*
G01X35700D01*
G02X35912Y251300I0J-212D01*
G01Y249700D01*
G02X35700Y249488I-212J0D01*
G01X34300D01*
G02X34088Y249700I0J212D01*
G01Y251300D01*
G37*
G36*
G01Y254800D02*
G02X34300Y255012I212J0D01*
G01X35700D01*
G02X35912Y254800I0J-212D01*
G01Y253200D01*
G02X35700Y252988I-212J0D01*
G01X34300D01*
G02X34088Y253200I0J212D01*
G01Y254800D01*
G37*
G36*
G01Y258300D02*
G02X34300Y258512I212J0D01*
G01X35700D01*
G02X35912Y258300I0J-212D01*
G01Y256700D01*
G02X35700Y256488I-212J0D01*
G01X34300D01*
G02X34088Y256700I0J212D01*
G01Y258300D01*
G37*
G36*
G01Y233800D02*
G02X34300Y234012I212J0D01*
G01X35700D01*
G02X35912Y233800I0J-212D01*
G01Y232200D01*
G02X35700Y231988I-212J0D01*
G01X34300D01*
G02X34088Y232200I0J212D01*
G01Y233800D01*
G37*
G36*
G01Y237300D02*
G02X34300Y237512I212J0D01*
G01X35700D01*
G02X35912Y237300I0J-212D01*
G01Y235700D01*
G02X35700Y235488I-212J0D01*
G01X34300D01*
G02X34088Y235700I0J212D01*
G01Y237300D01*
G37*
G36*
G01Y240800D02*
G02X34300Y241012I212J0D01*
G01X35700D01*
G02X35912Y240800I0J-212D01*
G01Y239200D01*
G02X35700Y238988I-212J0D01*
G01X34300D01*
G02X34088Y239200I0J212D01*
G01Y240800D01*
G37*
G36*
G01Y244300D02*
G02X34300Y244512I212J0D01*
G01X35700D01*
G02X35912Y244300I0J-212D01*
G01Y242700D01*
G02X35700Y242488I-212J0D01*
G01X34300D01*
G02X34088Y242700I0J212D01*
G01Y244300D01*
G37*
G36*
G01Y219800D02*
G02X34300Y220012I212J0D01*
G01X35700D01*
G02X35912Y219800I0J-212D01*
G01Y218200D01*
G02X35700Y217988I-212J0D01*
G01X34300D01*
G02X34088Y218200I0J212D01*
G01Y219800D01*
G37*
G36*
G01Y223300D02*
G02X34300Y223512I212J0D01*
G01X35700D01*
G02X35912Y223300I0J-212D01*
G01Y221700D01*
G02X35700Y221488I-212J0D01*
G01X34300D01*
G02X34088Y221700I0J212D01*
G01Y223300D01*
G37*
G36*
G01Y226800D02*
G02X34300Y227012I212J0D01*
G01X35700D01*
G02X35912Y226800I0J-212D01*
G01Y225200D01*
G02X35700Y224988I-212J0D01*
G01X34300D01*
G02X34088Y225200I0J212D01*
G01Y226800D01*
G37*
G36*
G01Y230300D02*
G02X34300Y230512I212J0D01*
G01X35700D01*
G02X35912Y230300I0J-212D01*
G01Y228700D01*
G02X35700Y228488I-212J0D01*
G01X34300D01*
G02X34088Y228700I0J212D01*
G01Y230300D01*
G37*
G36*
G01X39588Y199600D02*
G02X39800Y199812I212J0D01*
G01X41200D01*
G02X41412Y199600I0J-212D01*
G01Y198000D01*
G02X41200Y197788I-212J0D01*
G01X39800D01*
G02X39588Y198000I0J212D01*
G01Y199600D01*
G37*
G36*
G01X42588D02*
G02X42800Y199812I212J0D01*
G01X44200D01*
G02X44412Y199600I0J-212D01*
G01Y198000D01*
G02X44200Y197788I-212J0D01*
G01X42800D01*
G02X42588Y198000I0J212D01*
G01Y199600D01*
G37*
G36*
G01X45588D02*
G02X45800Y199812I212J0D01*
G01X47200D01*
G02X47412Y199600I0J-212D01*
G01Y198000D01*
G02X47200Y197788I-212J0D01*
G01X45800D01*
G02X45588Y198000I0J212D01*
G01Y199600D01*
G37*
G36*
G01Y204500D02*
G02X45800Y204712I212J0D01*
G01X47200D01*
G02X47412Y204500I0J-212D01*
G01Y202900D01*
G02X47200Y202688I-212J0D01*
G01X45800D01*
G02X45588Y202900I0J212D01*
G01Y204500D01*
G37*
G36*
G01X42588D02*
G02X42800Y204712I212J0D01*
G01X44200D01*
G02X44412Y204500I0J-212D01*
G01Y202900D01*
G02X44200Y202688I-212J0D01*
G01X42800D01*
G02X42588Y202900I0J212D01*
G01Y204500D01*
G37*
G36*
G01X39588D02*
G02X39800Y204712I212J0D01*
G01X41200D01*
G02X41412Y204500I0J-212D01*
G01Y202900D01*
G02X41200Y202688I-212J0D01*
G01X39800D01*
G02X39588Y202900I0J212D01*
G01Y204500D01*
G37*
G36*
G01X42388Y208600D02*
G02X42600Y208812I212J0D01*
G01X44000D01*
G02X44212Y208600I0J-212D01*
G01Y207000D01*
G02X44000Y206788I-212J0D01*
G01X42600D01*
G02X42388Y207000I0J212D01*
G01Y208600D01*
G37*
G36*
G01X45388D02*
G02X45600Y208812I212J0D01*
G01X47000D01*
G02X47212Y208600I0J-212D01*
G01Y207000D01*
G02X47000Y206788I-212J0D01*
G01X45600D01*
G02X45388Y207000I0J212D01*
G01Y208600D01*
G37*
G36*
G01Y213500D02*
G02X45600Y213712I212J0D01*
G01X47000D01*
G02X47212Y213500I0J-212D01*
G01Y211900D01*
G02X47000Y211688I-212J0D01*
G01X45600D01*
G02X45388Y211900I0J212D01*
G01Y213500D01*
G37*
G36*
G01X42388D02*
G02X42600Y213712I212J0D01*
G01X44000D01*
G02X44212Y213500I0J-212D01*
G01Y211900D01*
G02X44000Y211688I-212J0D01*
G01X42600D01*
G02X42388Y211900I0J212D01*
G01Y213500D01*
G37*
G36*
G01X31088Y247800D02*
G02X31300Y248012I212J0D01*
G01X32700D01*
G02X32912Y247800I0J-212D01*
G01Y246200D01*
G02X32700Y245988I-212J0D01*
G01X31300D01*
G02X31088Y246200I0J212D01*
G01Y247800D01*
G37*
G36*
G01Y251300D02*
G02X31300Y251512I212J0D01*
G01X32700D01*
G02X32912Y251300I0J-212D01*
G01Y249700D01*
G02X32700Y249488I-212J0D01*
G01X31300D01*
G02X31088Y249700I0J212D01*
G01Y251300D01*
G37*
G36*
G01Y254800D02*
G02X31300Y255012I212J0D01*
G01X32700D01*
G02X32912Y254800I0J-212D01*
G01Y253200D01*
G02X32700Y252988I-212J0D01*
G01X31300D01*
G02X31088Y253200I0J212D01*
G01Y254800D01*
G37*
G36*
G01Y258300D02*
G02X31300Y258512I212J0D01*
G01X32700D01*
G02X32912Y258300I0J-212D01*
G01Y256700D01*
G02X32700Y256488I-212J0D01*
G01X31300D01*
G02X31088Y256700I0J212D01*
G01Y258300D01*
G37*
G36*
G01Y233800D02*
G02X31300Y234012I212J0D01*
G01X32700D01*
G02X32912Y233800I0J-212D01*
G01Y232200D01*
G02X32700Y231988I-212J0D01*
G01X31300D01*
G02X31088Y232200I0J212D01*
G01Y233800D01*
G37*
G36*
G01Y237300D02*
G02X31300Y237512I212J0D01*
G01X32700D01*
G02X32912Y237300I0J-212D01*
G01Y235700D01*
G02X32700Y235488I-212J0D01*
G01X31300D01*
G02X31088Y235700I0J212D01*
G01Y237300D01*
G37*
G36*
G01Y240800D02*
G02X31300Y241012I212J0D01*
G01X32700D01*
G02X32912Y240800I0J-212D01*
G01Y239200D01*
G02X32700Y238988I-212J0D01*
G01X31300D01*
G02X31088Y239200I0J212D01*
G01Y240800D01*
G37*
G36*
G01Y244300D02*
G02X31300Y244512I212J0D01*
G01X32700D01*
G02X32912Y244300I0J-212D01*
G01Y242700D01*
G02X32700Y242488I-212J0D01*
G01X31300D01*
G02X31088Y242700I0J212D01*
G01Y244300D01*
G37*
G36*
G01Y219800D02*
G02X31300Y220012I212J0D01*
G01X32700D01*
G02X32912Y219800I0J-212D01*
G01Y218200D01*
G02X32700Y217988I-212J0D01*
G01X31300D01*
G02X31088Y218200I0J212D01*
G01Y219800D01*
G37*
G36*
G01Y223300D02*
G02X31300Y223512I212J0D01*
G01X32700D01*
G02X32912Y223300I0J-212D01*
G01Y221700D01*
G02X32700Y221488I-212J0D01*
G01X31300D01*
G02X31088Y221700I0J212D01*
G01Y223300D01*
G37*
G36*
G01Y226800D02*
G02X31300Y227012I212J0D01*
G01X32700D01*
G02X32912Y226800I0J-212D01*
G01Y225200D01*
G02X32700Y224988I-212J0D01*
G01X31300D01*
G02X31088Y225200I0J212D01*
G01Y226800D01*
G37*
G36*
G01Y230300D02*
G02X31300Y230512I212J0D01*
G01X32700D01*
G02X32912Y230300I0J-212D01*
G01Y228700D01*
G02X32700Y228488I-212J0D01*
G01X31300D01*
G02X31088Y228700I0J212D01*
G01Y230300D01*
G37*
G36*
G01X319026Y236350D02*
X316069D01*
G02Y239050I-69J1350D01*
G01X319031D01*
G02Y236350I69J-1350D01*
G01X319026D01*
G37*
G36*
G01X329939Y236762D02*
X329942Y236759D01*
X332041Y234668D01*
X332045Y234664D01*
G02X330148Y232742I-903J-1006D01*
G01X330145Y232745D01*
X328036Y234845D01*
X328033Y234848D01*
G02X329939Y236762I911J999D01*
G37*
G36*
G01X318550Y215226D02*
Y213169D01*
G02X315850I-1350J-69D01*
G01Y215231D01*
G02X318550I1350J69D01*
G01Y215226D01*
G37*
G36*
G01X322950Y210926D02*
Y208769D01*
G02X320250I-1350J-69D01*
G01Y210931D01*
G02X322950I1350J69D01*
G01Y210926D01*
G37*
G36*
G01X36300Y212122D02*
Y208373D01*
G02X33300I-1500J-73D01*
G01Y212127D01*
G02X36300I1500J73D01*
G01Y212122D01*
G37*
G36*
G01X33500Y203122D02*
Y199373D01*
G02X30500I-1500J-73D01*
G01Y203127D01*
G02X33500I1500J73D01*
G01Y203122D01*
G37*
G36*
G01X415689Y202750D02*
X418189D01*
X420250Y204811D01*
Y208689D01*
X419250Y209689D01*
Y211311D01*
X419705Y211766D01*
X419721Y211804D01*
G02X420471Y212554I1254J-504D01*
G01X420509Y212570D01*
X420689Y212750D01*
X422811D01*
X424750Y210811D01*
Y208311D01*
X425811Y207250D01*
X428811D01*
X435811Y200250D01*
X440311D01*
X441750Y198811D01*
Y192689D01*
X439311Y190250D01*
X437311D01*
X429311Y182250D01*
X422311D01*
X420811Y180750D01*
X416189D01*
X415372Y181567D01*
X415350Y181580D01*
G02X414678Y182250I965J1639D01*
G01X410311D01*
X407750Y179689D01*
Y178189D01*
X406311Y176750D01*
X405846D01*
X405810Y176736D01*
G02X404390I-710J1764D01*
G01X404354Y176750D01*
X393689D01*
X387250Y183189D01*
Y195311D01*
X389189Y197250D01*
X404559D01*
X404616Y197353D01*
G02X406984I1184J-653D01*
G01X407041Y197250D01*
X409811D01*
X411097Y195964D01*
G03X411635Y195939I283J283D01*
G02X413365I865J-1039D01*
G03X413903Y195964I255J308D01*
G01X414250Y196311D01*
Y201311D01*
X415689Y202750D01*
G37*
G36*
G01X307505Y124052D02*
X307509D01*
X309573Y124142D01*
X309578D01*
G02X309696Y121444I122J-1346D01*
G01X309691D01*
X307626Y121354D01*
X307621Y121353D01*
G02X307505Y124052I-121J1347D01*
G37*
G36*
G01X309107Y116351D02*
X307051Y116374D01*
X307046D01*
G02X307077Y119074I-52J1351D01*
G01X307081D01*
X309137Y119051D01*
X309142D01*
G02X309111Y116351I52J-1351D01*
G01X309107D01*
G37*
G36*
G01X389250Y113189D02*
Y120689D01*
X387250Y122689D01*
Y126311D01*
X388766Y127827D01*
X388778Y127885D01*
G02X390894Y128694I1322J-285D01*
G01X391033Y128594D01*
X392189Y129750D01*
X394689D01*
X395689Y130750D01*
X396675D01*
G02X398925I1125J-750D01*
G01X403958D01*
X403980Y130755D01*
G02X404820I420J-1855D01*
G01X404842Y130750D01*
X406811D01*
X410250Y127311D01*
Y122432D01*
G02X410822Y121739I-1139J-1523D01*
G01X413811Y118750D01*
X415208D01*
G03X415596Y119251I1J400D01*
G02X415724Y120252I1308J341D01*
G01X415750Y120297D01*
Y121815D01*
G02X417203Y123905I1101J785D01*
G01X417314Y123875D01*
X419189Y125750D01*
X424689D01*
X426031Y127092D01*
X425925Y127231D01*
G02X428157Y128750I1075J820D01*
G01X429811D01*
X430811Y127750D01*
X432949D01*
G03X433349Y128161I0J400D01*
G02X435215Y129450I1351J39D01*
G01X435338Y129399D01*
X436689Y130750D01*
X438811D01*
X440311Y129250D01*
X442811D01*
X446750Y125311D01*
Y117189D01*
X439811Y110250D01*
X433811D01*
X432250Y108689D01*
Y103689D01*
X431311Y102750D01*
X426189D01*
X423250Y105689D01*
Y109189D01*
X421689Y110750D01*
X410811D01*
X409811Y109750D01*
X392689D01*
X389250Y113189D01*
G37*
G36*
G01X253422Y56400D02*
X250573D01*
G02Y59400I-73J1500D01*
G01X253427D01*
G02Y56400I73J-1500D01*
G01X253422D01*
G37*
G36*
G01X261922Y56300D02*
X259073D01*
G02Y59300I-73J1500D01*
G01X261927D01*
G02Y56300I73J-1500D01*
G01X261922D01*
G37*
G36*
G01X197622Y52900D02*
X194773D01*
G02Y55900I-73J1500D01*
G01X197627D01*
G02Y52900I73J-1500D01*
G01X197622D01*
G37*
G36*
G01X181722D02*
X179073D01*
G02Y55900I-73J1500D01*
G01X181727D01*
G02Y52900I73J-1500D01*
G01X181722D01*
G37*
G36*
G01X189622Y52800D02*
X186938D01*
G02Y55800I-73J1500D01*
G01X189627D01*
G02Y52800I73J-1500D01*
G01X189622D01*
G37*
G54D41*
X37600Y198800D03*
Y203700D03*
X40400Y207800D03*
Y212700D03*
G54D39*
X144000Y67875D03*
Y147125D03*
G54D38*
X42717Y270472D03*
X235630Y75590D03*
X492520Y262598D03*
X761417Y22798D03*
G54D40*
X235630Y174016D03*
X498425Y22798D03*
X755512Y262598D03*
G54D37*
X42717Y191732D03*
G54D34*
X350197Y231103D03*
G54D35*
X11500Y68500D03*
X12000Y279000D03*
X816000Y280000D03*
G54D36*
X45669Y77185D03*
Y172460D03*
%LPC*%
G75*
G36*
G01X390811Y126250D02*
X392811Y128250D01*
X395311D01*
X396311Y129250D01*
X396675D01*
G03X398925I1125J750D01*
G01X406189D01*
X408750Y126689D01*
Y121689D01*
X413189Y117250D01*
X416311D01*
X417250Y118189D01*
Y118277D01*
X417380Y118325D01*
G03Y120857I-476J1266D01*
G01X417250Y120905D01*
Y121301D01*
X417373Y121353D01*
G03X418203Y122564I-522J1247D01*
G01X418205Y122644D01*
X419811Y124250D01*
X425311D01*
X428311Y127250D01*
X429189D01*
X430189Y126250D01*
X434311D01*
X434927Y126866D01*
X434985Y126878D01*
G03X436022Y127915I-285J1322D01*
G01X436034Y127973D01*
X437311Y129250D01*
X438189D01*
X439689Y127750D01*
X442189D01*
X445250Y124689D01*
Y117811D01*
X439189Y111750D01*
X433189D01*
X430750Y109311D01*
Y104311D01*
X430689Y104250D01*
X426811D01*
X424750Y106311D01*
Y109811D01*
X422311Y112250D01*
X410189D01*
X409189Y111250D01*
X393311D01*
X390750Y113811D01*
Y121311D01*
X388750Y123311D01*
Y125689D01*
X389311Y126250D01*
X390031D01*
G03X390169I69J1350D01*
G01X390811D01*
G37*
G36*
G01X422134Y210603D02*
G02X422759Y210680I343J-206D01*
G01X423250Y210189D01*
Y207689D01*
X425189Y205750D01*
X428189D01*
X435189Y198750D01*
X439689D01*
X440250Y198189D01*
Y193311D01*
X438689Y191750D01*
X436689D01*
X428689Y183750D01*
X421689D01*
X420189Y182250D01*
X416811D01*
X415311Y183750D01*
X409689D01*
X406250Y180311D01*
Y178811D01*
X405689Y178250D01*
X394311D01*
X388750Y183811D01*
Y194689D01*
X389811Y195750D01*
X404838D01*
G03X406762I962J950D01*
G01X409189D01*
X410689Y194250D01*
X411315D01*
G03X413685I1185J650D01*
G01X414311D01*
X415750Y195689D01*
Y200689D01*
X416311Y201250D01*
X418811D01*
X421750Y204189D01*
Y209311D01*
X421564Y209497D01*
G02X421648Y210127I283J283D01*
G03X422134Y210603I-673J1173D01*
G37*
G36*
G01X594189Y236750D02*
X590189Y232750D01*
X583311D01*
X582750Y233311D01*
Y240689D01*
X585250Y243189D01*
Y281189D01*
X585811Y281750D01*
X639689D01*
X640250Y281189D01*
Y246811D01*
X636629Y243189D01*
X630189Y236750D01*
X594189D01*
G37*
%LPD*%
G75*
G54D15*
X17500Y190200D03*
X16844Y203100D03*
X13090Y231129D03*
Y234899D03*
X7600Y240861D03*
Y237091D03*
X13590Y242940D03*
Y254751D03*
X7600Y252672D03*
Y248902D03*
Y260713D03*
X13590Y258521D03*
Y246710D03*
X16900Y269000D03*
X7600Y264483D03*
X28400Y81400D03*
X30000Y136000D03*
X29700Y141200D03*
X26500Y181800D03*
X33500Y178100D03*
X33150Y181500D03*
X29400Y180000D03*
X23100Y181800D03*
X33500Y196100D03*
X32000Y203200D03*
Y199300D03*
X41200Y90300D03*
X42000Y96000D03*
X41500Y100800D03*
X40500Y124300D03*
X37600Y198800D03*
X37900Y195300D03*
X40400Y212700D03*
X34800Y208300D03*
X40400Y207800D03*
X34800Y212200D03*
X37600Y203700D03*
X44861Y227261D03*
X37900Y219000D03*
Y222500D03*
Y229500D03*
Y226000D03*
Y240000D03*
Y243500D03*
Y233000D03*
X38000Y236500D03*
X44400Y250400D03*
X37900Y257500D03*
Y254000D03*
Y247000D03*
X38000Y250500D03*
X46800Y274500D03*
X62900Y79900D03*
X60800Y87500D03*
X53500Y120400D03*
X57600Y136900D03*
X56100Y130700D03*
X52643Y130800D03*
X58000Y141750D03*
X58800Y177000D03*
X51860Y187640D03*
Y191410D03*
X59379Y184380D03*
X55720D03*
X57400Y210700D03*
X57009Y230009D03*
X57600Y226600D03*
X57500Y223200D03*
X57287Y219806D03*
X56724Y243300D03*
X56800Y249613D03*
X58102Y246471D03*
X57800Y253900D03*
X50000Y270000D03*
X57800Y264100D03*
X64700Y272500D03*
X57800Y267500D03*
X80031Y40357D03*
X76411D03*
X79700Y67500D03*
X79115Y60979D03*
X69235Y99735D03*
X68200Y94900D03*
Y91500D03*
X66500Y128000D03*
X65500Y123800D03*
X74800Y191000D03*
X72600Y244800D03*
X75600Y246700D03*
X79000Y246900D03*
X69400Y246000D03*
X75300Y259900D03*
X78200Y275600D03*
X71800Y268800D03*
X66800Y275200D03*
X74000Y271400D03*
X92159Y40357D03*
X88700Y54400D03*
X85300D03*
X90600Y63200D03*
X94000Y63300D03*
X82885Y60979D03*
X90000Y91000D03*
X91500Y84000D03*
X94500Y76200D03*
X89800Y87300D03*
X86100Y97700D03*
X90500Y101000D03*
X86500Y113500D03*
X80500D03*
X85500Y135400D03*
X83500Y191000D03*
X86900D03*
X84700Y197100D03*
X92900Y204008D03*
X89500Y204000D03*
X85898Y200598D03*
X95200Y216200D03*
X90812Y215000D03*
X80563Y214700D03*
X88900Y246700D03*
X82400Y246600D03*
X82100Y259600D03*
X80500Y269500D03*
X83900D03*
X95779Y40357D03*
X107907D03*
X109700Y60000D03*
X103450Y54400D03*
X100050D03*
X109600Y63700D03*
X96200Y60700D03*
X97900Y76200D03*
X106100Y158700D03*
X97100Y189200D03*
X110000Y201900D03*
X107740Y204460D03*
X102000Y203200D03*
X100600Y221100D03*
X110166Y239500D03*
X109500Y258300D03*
X97600Y246500D03*
X104900Y248800D03*
X120000Y40700D03*
X123655Y40357D03*
X111527D03*
X120200Y45610D03*
X119200Y57400D03*
X115800D03*
X111200Y67200D03*
X121170Y80900D03*
X121295Y77502D03*
X126000Y86200D03*
X125787Y78813D03*
X120700Y135500D03*
X118500Y125500D03*
X112550Y142800D03*
X119600Y143300D03*
X111900Y209000D03*
X112800Y225400D03*
X112700Y221200D03*
Y231400D03*
X136600Y44800D03*
X139403Y40357D03*
X127275D03*
X138000Y49800D03*
X138574Y57924D03*
X131600Y57400D03*
X135000D03*
X136469Y89902D03*
X130315Y90533D03*
X134200Y86100D03*
X137138Y76512D03*
X129300Y84900D03*
X136600Y93300D03*
X133558Y91779D03*
X136500Y104923D03*
X130000Y121000D03*
X136540Y108620D03*
X133975Y129141D03*
X130563Y125200D03*
X127500Y129180D03*
X126950Y125200D03*
X133786Y134700D03*
X130300Y135000D03*
X135412Y141400D03*
X138600Y146300D03*
X131500Y149000D03*
X136156Y138025D03*
X131762Y141796D03*
X127200Y158700D03*
X137300Y158900D03*
X140800D03*
X140000Y195500D03*
X137100Y188900D03*
X128000Y203300D03*
X143023Y40357D03*
X155151D03*
X144995Y57995D03*
X155290Y48610D03*
X143688Y48350D03*
X147400Y60400D03*
X147315Y54400D03*
X150715D03*
X153000Y67800D03*
X150894Y76497D03*
X154294Y76506D03*
X150670Y102720D03*
X154550Y106200D03*
X151080Y99344D03*
X154550Y102800D03*
X150670Y115500D03*
Y118900D03*
X157229Y119218D03*
X153693Y124807D03*
X147808Y145208D03*
X142900Y138595D03*
X146400D03*
X150804Y158896D03*
X144500Y158900D03*
X146980Y200580D03*
X153000Y201900D03*
X153500Y210000D03*
X146396Y207675D03*
X142997Y207891D03*
X150000Y210100D03*
X146500Y236500D03*
X146000Y231000D03*
X155300Y254000D03*
X144200Y270700D03*
X158771Y40357D03*
X170899D03*
X159060Y48610D03*
X170290Y49600D03*
X166463Y54400D03*
X163063D03*
X164000Y65000D03*
X172199Y91591D03*
X172300Y107189D03*
X158305Y112180D03*
X157500Y149025D03*
X158500Y161820D03*
X161900Y161700D03*
X167581Y164084D03*
X170910Y173840D03*
X167140D03*
X165900Y181500D03*
X163700Y178900D03*
X165700Y254000D03*
X174519Y40357D03*
X186647D03*
X174060Y49600D03*
X186865Y54300D03*
X181800Y54400D03*
X179000D03*
X179800Y65700D03*
X176900Y67500D03*
X180700Y78500D03*
X174900Y77700D03*
X183726Y106353D03*
X187500Y106500D03*
X173000Y97000D03*
X183344Y94056D03*
X179400Y94200D03*
X181732Y97500D03*
X178000Y97300D03*
X175787Y127000D03*
X176700Y144875D03*
X177200Y148700D03*
X181000Y167500D03*
X180931Y172985D03*
X177159Y172900D03*
X186300Y172400D03*
X174739Y207381D03*
X187000Y209500D03*
X198073Y40395D03*
X194445D03*
X190267Y40357D03*
X189700Y54300D03*
X197700Y54400D03*
X194700D03*
X190100Y68700D03*
X193500D03*
X194075Y80360D03*
X197845D03*
X202200Y89500D03*
X191500Y94100D03*
X188900Y91800D03*
X193005Y97155D03*
X195989Y95300D03*
X189106Y97235D03*
X201650Y111200D03*
X201899Y134200D03*
X194900Y124200D03*
X197140Y152010D03*
X194623Y149723D03*
X191200Y181068D03*
X199441Y187547D03*
X199392Y190947D03*
X202761Y186811D03*
X195630Y192770D03*
X198198Y206374D03*
X194800Y206100D03*
X201596Y206504D03*
X195000Y234000D03*
X205300Y54900D03*
X208700D03*
X214942Y67242D03*
X211600Y82100D03*
X212300Y85500D03*
X207200Y106000D03*
X209259Y113771D03*
Y117430D03*
X206605Y121741D03*
X209900Y120900D03*
X205380Y134200D03*
X210547Y139028D03*
X206790Y139040D03*
X215100Y194200D03*
X207861Y188540D03*
X215100Y199400D03*
X205000Y206500D03*
X215384Y202984D03*
X216000Y219500D03*
X208800D03*
X212500D03*
X206000Y234000D03*
X229300Y42950D03*
X232591Y43057D03*
X219900Y39100D03*
X223475Y53300D03*
X219899Y56800D03*
X233981Y59125D03*
X221400Y64500D03*
X230400Y63000D03*
X223800Y61700D03*
X230000Y66400D03*
X226500Y94450D03*
X227850Y97575D03*
X230875Y106300D03*
X227894Y104600D03*
X232600Y95300D03*
X227800Y101200D03*
X233452Y108588D03*
X228000Y108304D03*
Y139700D03*
X232921Y167505D03*
X227870Y170252D03*
X224200Y180200D03*
X232560Y204250D03*
X227000Y275500D03*
X236211Y43057D03*
X245385Y40357D03*
X241765D03*
X244400Y50600D03*
X235400Y63400D03*
X240297D03*
X243200Y73700D03*
X240300Y67200D03*
X246600Y73700D03*
X244759Y85200D03*
X236700Y88500D03*
X241200Y94900D03*
X244800Y100700D03*
X235075Y105600D03*
X234875Y139290D03*
Y143060D03*
X244715Y159785D03*
X239900Y180600D03*
X247596Y174667D03*
X240119Y183993D03*
X240100Y191000D03*
X246689Y196687D03*
X254600Y41100D03*
X265140Y40490D03*
X259000Y57800D03*
X250500Y57900D03*
X262000Y57800D03*
X253500Y57900D03*
X264500Y73100D03*
X253700Y75875D03*
X250300Y73800D03*
X264125Y79350D03*
X259820Y103454D03*
X262131Y100959D03*
X258634Y95850D03*
X263775Y140327D03*
X257977Y163423D03*
X264600Y173100D03*
X257687Y169870D03*
X253500Y174360D03*
X261300Y188300D03*
X253300Y189834D03*
X262700Y191500D03*
X261200Y209700D03*
X263600Y239850D03*
Y252700D03*
X257500Y266645D03*
X260500Y264630D03*
X269800Y44800D03*
X275300Y44900D03*
X278700Y44800D03*
X268910Y40490D03*
X278868Y56000D03*
X271000Y57500D03*
X268000D03*
X275200Y78700D03*
X275900Y88200D03*
X280100Y89100D03*
X272200Y108352D03*
X272185Y111831D03*
X278075Y116475D03*
X272300Y129442D03*
X268900Y129386D03*
X280400Y129225D03*
X272300Y149900D03*
X267187Y149800D03*
X278000Y141900D03*
X273900Y156198D03*
X270500Y163200D03*
X274100Y163300D03*
X267456Y160156D03*
X267100Y156200D03*
X272380Y159240D03*
X270500Y156250D03*
X268283Y173035D03*
X278300Y173300D03*
X276910Y189400D03*
X273060Y189374D03*
X266140Y191850D03*
X270341Y211835D03*
X278450Y216800D03*
X265259Y216659D03*
X270774Y222226D03*
X275400Y237900D03*
X267275Y253400D03*
X265500Y249300D03*
X269800Y250700D03*
X278700Y254240D03*
X275300Y254100D03*
X267000Y271300D03*
X284758Y40490D03*
X280988D03*
X286800Y57900D03*
X290200D03*
X288400Y94200D03*
X288100Y99500D03*
X281005Y99105D03*
X281475Y116475D03*
X286500Y119900D03*
X286600Y136000D03*
X287071Y173154D03*
X282950Y181350D03*
X282460Y189400D03*
X286300Y191885D03*
X293300Y212400D03*
X291201Y225025D03*
X287802Y225200D03*
X287600Y238100D03*
X287400Y254100D03*
X295500Y253500D03*
X281599Y261799D03*
X287250Y269250D03*
X296736Y40490D03*
X300506D03*
X300900Y46900D03*
X308200Y57400D03*
X304800D03*
X297150Y91100D03*
X309400Y82100D03*
X299800Y85950D03*
Y82300D03*
X304400Y88400D03*
X301300Y97000D03*
X301600Y93300D03*
X303400Y98500D03*
X303376Y95200D03*
X299300Y98500D03*
X296564Y136311D03*
Y127500D03*
X296531Y133061D03*
X301109Y146156D03*
X300700Y142850D03*
X297000Y160200D03*
X307231Y164059D03*
X310579Y182800D03*
X306612Y171882D03*
X304400Y182000D03*
X302591Y173906D03*
X309112Y171960D03*
X309200Y180500D03*
X305091Y173888D03*
X301745Y181788D03*
X307200Y182000D03*
X296600Y189100D03*
X305300Y203125D03*
X307300Y224900D03*
X304400D03*
X309900D03*
X298900Y253300D03*
X309400Y253600D03*
X306000D03*
X302600D03*
X304300Y262900D03*
X309000Y266700D03*
X311300Y277800D03*
X321900Y44000D03*
X312484Y40690D03*
X316254D03*
X314800Y48625D03*
X311950Y50800D03*
X320400Y48600D03*
X324000Y54900D03*
X324176Y48600D03*
X315800Y57400D03*
X319200D03*
X312400Y79700D03*
X312150Y100682D03*
X326000Y254100D03*
X315500D03*
X322500Y254200D03*
X319000D03*
X311400Y269200D03*
X326100Y267000D03*
X318600Y264300D03*
X313824Y280255D03*
X316945Y281606D03*
X316400Y276800D03*
X319400Y278800D03*
X322700Y277700D03*
X321600Y282500D03*
X325100Y281500D03*
X331931Y40995D03*
X328303D03*
X331300Y48475D03*
X327577D03*
X327400Y54900D03*
X333600Y63800D03*
X356432Y43657D03*
X356971Y37700D03*
X349900Y263800D03*
X342600Y277900D03*
X364600Y44298D03*
X367497Y41042D03*
X363604D03*
X371457Y37642D03*
X367520D03*
X366484Y47129D03*
X362626Y47068D03*
X366700Y68700D03*
X369500Y237200D03*
Y240600D03*
X373000Y242300D03*
X369500Y234600D03*
X373000Y236000D03*
Y238900D03*
X369500Y244000D03*
X385300Y47000D03*
X388000Y72963D03*
X382700Y275300D03*
X386100D03*
X379300D03*
X394229Y241128D03*
X391788Y238760D03*
X399438Y243839D03*
X401838Y246248D03*
X390500Y268800D03*
X393000Y275000D03*
X400900Y273000D03*
X391000Y265000D03*
X417000Y258000D03*
X416128Y272896D03*
X425400Y9103D03*
X422000D03*
X428800D03*
X432200D03*
X430000Y21500D03*
Y27358D03*
X424543Y22208D03*
Y27900D03*
X426405Y25054D03*
X427000Y17000D03*
X423500Y16885D03*
X423000Y43900D03*
X430000Y30758D03*
X424536Y34800D03*
X430000Y34158D03*
X424599Y31300D03*
X422986Y40350D03*
X430000Y244450D03*
X426600D03*
X420000Y244000D03*
X420500Y257800D03*
X433129Y245783D03*
X423600Y246700D03*
X423000Y274000D03*
X433300Y274100D03*
X426600D03*
X429900Y274940D03*
X442100Y7006D03*
X437061Y10393D03*
X434900Y6925D03*
X446800Y9900D03*
X438300Y6925D03*
X449600Y5900D03*
X446200D03*
X446100Y18700D03*
X441390Y28680D03*
X436240Y26300D03*
X449734Y18681D03*
X441281Y17025D03*
X436100Y30900D03*
X436106Y34506D03*
X435700Y243250D03*
X440600Y274300D03*
X449400Y273700D03*
X436600Y275000D03*
X450200Y9800D03*
X451300Y21700D03*
X464000Y275200D03*
X460400D03*
X452500D03*
X469000D03*
X472400Y275100D03*
X466500Y272800D03*
X472101Y266090D03*
X475500Y265900D03*
X479000D03*
X493000Y119299D03*
X495400Y183500D03*
X482400Y266200D03*
X498500Y88995D03*
X508000Y119500D03*
X511500D03*
X504400Y183400D03*
X510675Y209700D03*
X505315Y268500D03*
X497002Y275400D03*
X522280Y89810D03*
X515502Y88998D03*
X518902Y88987D03*
X518200Y183400D03*
X514800D03*
X528985Y89975D03*
X533267Y89634D03*
X539574Y88990D03*
X533000Y119500D03*
X536400D03*
X528100D03*
X528400Y145041D03*
X541550Y183550D03*
X534750Y183600D03*
X538150D03*
X530214Y183481D03*
X531000Y228350D03*
X552900Y89100D03*
X542950Y89400D03*
X555500Y183500D03*
X548354Y183600D03*
X551754D03*
X548300Y209700D03*
X566000Y89100D03*
X572845Y183300D03*
X566897Y183405D03*
X561900Y183600D03*
X564398Y183481D03*
X569395Y183300D03*
X558300Y210000D03*
X561000Y222700D03*
X561196Y227366D03*
X564200Y224000D03*
X575000Y89100D03*
X587500Y88913D03*
X578400Y89100D03*
X588600Y124700D03*
X584800Y183300D03*
X576295Y183400D03*
X588475Y183300D03*
X578795D03*
X573600Y190100D03*
X586800Y213200D03*
X583800Y207200D03*
X580350Y207250D03*
X599500Y87500D03*
X590898Y89045D03*
X593400Y126000D03*
X592200Y145000D03*
X595744Y145041D03*
X599150Y180300D03*
X593475Y183275D03*
X601750Y182500D03*
X594350Y187725D03*
X591850D03*
X591363Y208387D03*
X602800Y203225D03*
X601200Y207700D03*
X612120Y121750D03*
X608360Y121800D03*
X608300Y144890D03*
X618500Y159000D03*
X605600Y186650D03*
X609345Y190100D03*
X607500Y188300D03*
X616100Y197400D03*
X634000Y97500D03*
X630700Y100500D03*
X624726Y107395D03*
X621100Y124900D03*
X625500Y159000D03*
X629000D03*
X622000D03*
X633319Y155008D03*
X631900Y175850D03*
X634748Y177708D03*
X633100Y198300D03*
X626300Y198250D03*
X629700Y198300D03*
X622873Y204200D03*
X642823Y88477D03*
X640677Y91115D03*
X638500Y94000D03*
X635000Y110500D03*
X638000Y107400D03*
X648500Y144000D03*
X636719Y154972D03*
X643500Y155000D03*
X640110Y155272D03*
X640461Y181410D03*
X642600Y186400D03*
X646000D03*
X636500Y198300D03*
X653600Y122400D03*
X656477Y148033D03*
X656642Y151430D03*
X656200Y144000D03*
X650500Y155000D03*
X661000Y173800D03*
X657722Y193800D03*
X661600Y197300D03*
X654851Y191978D03*
X663800Y199900D03*
X673100Y179455D03*
X673044Y190456D03*
X668732Y204555D03*
X666446Y202037D03*
X682600Y114300D03*
X689400Y178900D03*
X689547Y175500D03*
X686700Y187400D03*
X687456Y183944D03*
X705145Y93500D03*
X707209Y97500D03*
X698970Y118149D03*
X699241Y114759D03*
X709500Y143500D03*
X709900Y139900D03*
X701245Y183800D03*
X718900Y94000D03*
X726800Y95500D03*
X724200Y108400D03*
X714000Y118500D03*
X727448Y128893D03*
X714900Y131900D03*
X718200Y147000D03*
Y150400D03*
X718825Y155453D03*
X712700Y155978D03*
X724400Y176025D03*
X725500Y195500D03*
X727400Y227400D03*
X736900Y98500D03*
X730200Y94900D03*
X742100Y118200D03*
X736300Y118000D03*
X729400Y120200D03*
X732000Y122700D03*
X728900Y132976D03*
X727800Y136600D03*
X740300Y164700D03*
X727800Y176600D03*
X733000Y176200D03*
X739900Y212800D03*
X731000Y210200D03*
X739800Y216300D03*
X750100Y16100D03*
X749500Y101500D03*
X751300Y118200D03*
X754000Y115100D03*
X748800Y115800D03*
X757900Y124700D03*
X743100Y195500D03*
X743000Y211000D03*
X744100Y221900D03*
X743800Y215900D03*
X758916Y104250D03*
X762304Y103957D03*
X765500Y112000D03*
X769800Y133000D03*
X759400Y131000D03*
X771300Y140200D03*
X766600Y139800D03*
X762000Y281000D03*
X765400D03*
X774500Y31307D03*
X778000D03*
X787600Y183300D03*
X787800Y179900D03*
X793000Y174500D03*
X805500Y128000D03*
G54D20*
X196800Y62600D03*
X199600Y160100D03*
X502500Y6200D03*
X538300Y15200D03*
X699000Y162255D03*
X756400Y110500D03*
X786500Y13500D03*
X782000Y137000D03*
X790500Y11000D03*
X799000Y121500D03*
Y125500D03*
X800400Y158500D03*
X799900Y168800D03*
X811000Y130000D03*
Y134000D03*
X809000Y149200D03*
X811000Y138000D03*
X811200Y141600D03*
X809500Y156900D03*
X809600Y160500D03*
X809700Y164300D03*
G54D13*
X15400Y118000D03*
X10900D03*
X15500Y122800D03*
X15000Y127500D03*
X11000Y122800D03*
X10500Y127500D03*
X11500Y163700D03*
Y159000D03*
X7000Y163700D03*
Y159000D03*
X33000Y105000D03*
X30200Y145000D03*
Y149200D03*
X34000Y161500D03*
X30300Y157600D03*
X30200Y153400D03*
X37500Y105000D03*
X42000D03*
X37500Y264000D03*
X63500Y43500D03*
Y57500D03*
Y48000D03*
Y52500D03*
X63200Y194900D03*
X68500Y47500D03*
X73500Y48000D03*
X68000Y52500D03*
X70900Y193800D03*
X82000Y177500D03*
X92800Y285600D03*
X104000Y106600D03*
Y115500D03*
Y111000D03*
X100000Y267400D03*
X100700Y262900D03*
X97500Y285450D03*
X102000D03*
X106500Y285550D03*
X110700D03*
X119400Y106700D03*
X123800Y102500D03*
X123900Y106700D03*
X119400Y102300D03*
Y115900D03*
Y111200D03*
X123900Y115900D03*
Y111200D03*
X113200Y146700D03*
X113100Y151000D03*
X117500Y146950D03*
X119000Y159100D03*
X114700Y158800D03*
X116500Y211200D03*
X134100Y96600D03*
X128500Y165000D03*
X129500Y252500D03*
X129000Y268000D03*
X166500Y241000D03*
X189000Y87700D03*
X192500Y161900D03*
X192600Y166700D03*
X201200Y164200D03*
X216261Y74846D03*
X212300Y157300D03*
X212600Y161500D03*
X217000Y252900D03*
X217200Y258000D03*
X226900Y133300D03*
X234525Y239250D03*
X229700Y234700D03*
X225300Y239200D03*
X234525Y243450D03*
X229725D03*
X225300Y243400D03*
X234525Y234800D03*
X225300D03*
X229675Y239000D03*
X221300Y255400D03*
X240130Y77300D03*
X236400Y95100D03*
X240565Y113365D03*
X249350Y199400D03*
X247500Y239250D03*
X243300Y235050D03*
X247500Y243450D03*
X243300D03*
X238900D03*
X243300Y239250D03*
X247500Y235050D03*
X238925Y235000D03*
Y239200D03*
X258400Y65600D03*
X252350Y202350D03*
X251700Y239250D03*
Y243450D03*
X253000Y267000D03*
X278200Y281350D03*
X294800Y94100D03*
X282686Y281336D03*
X339638Y67138D03*
X334500Y266300D03*
X334300Y270500D03*
X335700Y278751D03*
X331500D03*
X345089Y73089D03*
X353500Y71900D03*
X357000Y69500D03*
X349300Y83000D03*
X345100D03*
X354200Y76400D03*
X343600Y270500D03*
X371400Y42500D03*
X371500Y47000D03*
X359800Y72700D03*
X362700Y69600D03*
X380000Y38100D03*
X375600Y42500D03*
X380300D03*
X375700Y47000D03*
X380295Y46779D03*
X496711Y248999D03*
X527000Y225500D03*
X659811Y260757D03*
X657500Y258400D03*
X661308Y263698D03*
X655500Y270500D03*
X657787Y264179D03*
X656000Y261400D03*
X655523Y266616D03*
X658667Y267622D03*
X721200Y65100D03*
X732000Y63500D03*
X753500Y24007D03*
Y20007D03*
Y28507D03*
X755500Y16000D03*
X770500Y13007D03*
X767500Y24007D03*
X760500Y29000D03*
X761000Y16007D03*
X767500Y28507D03*
Y19507D03*
X764200Y44200D03*
X767500Y33207D03*
X759000Y37507D03*
X764500Y54000D03*
X764300Y49200D03*
X769500Y50000D03*
X761000Y58500D03*
X787500Y93000D03*
X783000D03*
X785830Y188700D03*
X785400Y202800D03*
X789000Y204979D03*
X789200Y214200D03*
Y209800D03*
X784500Y222500D03*
X789000Y223500D03*
X789200Y218700D03*
X786000Y228000D03*
Y232400D03*
X786200Y236900D03*
X786300Y241500D03*
X785000Y245800D03*
Y250200D03*
Y254900D03*
X792000Y83000D03*
X796500D03*
X792000Y87700D03*
X796500D03*
X799200Y98600D03*
X803100Y106000D03*
X799200Y102800D03*
X799000Y107100D03*
X803500Y116700D03*
Y112500D03*
X799000Y116100D03*
Y111900D03*
X789910Y187679D03*
X794110D03*
X798310Y187779D03*
X793500Y204979D03*
Y223500D03*
X793200Y228400D03*
Y232600D03*
Y237200D03*
Y242400D03*
X793300Y247200D03*
X795300Y260800D03*
X795400Y251700D03*
X795300Y256500D03*
Y265000D03*
X810100Y275000D03*
X812035Y271067D03*
X810100Y267339D03*
X812000Y263500D03*
G54D18*
X42717Y270472D03*
X235630Y75590D03*
X492520Y262598D03*
D03*
X761417Y22798D03*
D03*
X794032Y27032D03*
X804032Y37032D03*
Y47032D03*
X794032Y37032D03*
Y47032D03*
X804032Y57032D03*
X794032D03*
Y67032D03*
G54D22*
X235630Y174016D03*
X498425Y22798D03*
D03*
X755512Y262598D03*
D03*
G54D24*
X303610Y110800D03*
X309000Y114700D03*
X306700D03*
X309194Y117700D03*
X306994Y117725D03*
X304149Y128349D03*
X307854Y130539D03*
X309700Y122796D03*
X309500Y132925D03*
X307298Y132697D03*
X307500Y122700D03*
X305050Y151150D03*
X309000Y137600D03*
X306961Y153717D03*
X306696Y158610D03*
X309000Y158806D03*
X309220Y153698D03*
X305800Y195400D03*
X303500D03*
X303480Y189100D03*
X301300Y188700D03*
X309700Y187997D03*
X307500Y188000D03*
X317641Y90956D03*
X325081Y100631D03*
X322075Y100650D03*
X323120Y92400D03*
X319520Y92419D03*
X318900Y98000D03*
X317600Y93625D03*
X326162Y91438D03*
X315950Y98650D03*
X320992Y112180D03*
X319096Y113300D03*
X319418Y123225D03*
X315451Y123219D03*
X323900Y129900D03*
X325418Y127349D03*
X325746Y133702D03*
X323300Y147046D03*
X326322Y138434D03*
X325763Y141958D03*
X325200Y149319D03*
X319704Y162804D03*
X323000Y153900D03*
X324029Y166384D03*
X326234Y153969D03*
X323500Y180063D03*
X323121Y182913D03*
X326408Y182292D03*
X316844Y196010D03*
X319801Y194890D03*
X326550Y191600D03*
X322256Y198618D03*
X323331Y196696D03*
X325642Y202325D03*
X321600Y208700D03*
Y211000D03*
X317200Y213100D03*
Y215300D03*
X316000Y237700D03*
X319100D03*
X329300Y87300D03*
X331200Y88600D03*
X330100Y100200D03*
Y98000D03*
X336750Y93500D03*
Y95704D03*
X328000Y92700D03*
X330900Y93400D03*
X333313Y103693D03*
X329415Y119923D03*
X333601Y120500D03*
X333534Y118040D03*
X333434Y106668D03*
X341200Y112569D03*
X338768Y116755D03*
Y119755D03*
X329308Y122386D03*
X338329Y135665D03*
X329031Y125428D03*
X335303Y135178D03*
X336900Y127600D03*
X333977Y127678D03*
X327854Y130434D03*
X338470Y138177D03*
X335450Y150900D03*
X327963Y142008D03*
X335514Y138220D03*
X338320Y141300D03*
X327390Y149106D03*
X336920Y146130D03*
X329421Y138228D03*
X327696Y146108D03*
X330163Y142008D03*
X332478Y138255D03*
X341342Y138224D03*
X333750Y145950D03*
X339491Y143163D03*
X329800Y150800D03*
X332000D03*
X330300Y158546D03*
X339784Y161847D03*
X335499Y153846D03*
X327800Y161500D03*
X336900Y161600D03*
X336800Y164434D03*
X341390Y153991D03*
X329161Y153830D03*
X335964Y158512D03*
X341400Y156700D03*
X331000Y164500D03*
X330900Y161700D03*
X333000Y158300D03*
X339747Y164478D03*
X339300Y174100D03*
X330821Y177402D03*
X329442Y169463D03*
X327708Y177241D03*
X332353Y169522D03*
X337000Y174102D03*
X327600Y174174D03*
X330027Y174119D03*
X334700Y174100D03*
X336915Y177423D03*
X337863Y180545D03*
X330280Y180900D03*
X332500D03*
X335400Y196300D03*
X337800Y189200D03*
X326850Y193900D03*
X329972Y196400D03*
Y193559D03*
X333996Y192063D03*
X334707Y189383D03*
X337800Y192200D03*
X329313Y188000D03*
X335739Y199317D03*
X336500Y204600D03*
X338926Y211674D03*
X338967Y209455D03*
X331658Y212660D03*
X327216Y203902D03*
X328510Y218320D03*
X327024Y220024D03*
X337307Y217961D03*
X331616Y214860D03*
X337341Y215731D03*
X328945Y235846D03*
X331142Y233658D03*
X346596Y118163D03*
Y115163D03*
X343570Y112561D03*
X346495Y130000D03*
X349149Y124141D03*
X351500Y136000D03*
X343000Y126200D03*
X343146Y128473D03*
X347641Y133479D03*
X342533Y133822D03*
X357300Y128600D03*
X355400Y137100D03*
X354300Y128600D03*
X346300Y143000D03*
X355447Y146528D03*
X344500Y141700D03*
X348675Y143326D03*
X348743Y146072D03*
X346000Y146043D03*
X346450Y149120D03*
X348432Y164844D03*
X346944Y156775D03*
X350550Y153280D03*
X344300Y153800D03*
X344090Y156690D03*
X352000Y162000D03*
X348700Y161700D03*
X351600Y164300D03*
X355400Y152900D03*
X350700Y155600D03*
X345900Y161700D03*
X342188Y183361D03*
X347200Y174300D03*
X344165Y169466D03*
X352200Y171800D03*
X347500Y169500D03*
X351600Y169600D03*
X353302Y182993D03*
X342233Y185639D03*
X356900Y186100D03*
X349600Y194800D03*
X342339Y192225D03*
X342342Y190024D03*
X349100Y191900D03*
X353625Y195045D03*
Y192045D03*
X356600Y195700D03*
X356700Y193300D03*
X345503Y193474D03*
X345500Y190500D03*
X349100Y189700D03*
X353342Y186124D03*
X345500Y184500D03*
X345631Y187420D03*
X353594Y210707D03*
X347593Y210277D03*
X353385Y212898D03*
X343242Y213690D03*
X347664Y212476D03*
X343198Y215910D03*
X371900Y85400D03*
X364800Y91200D03*
X368600Y90700D03*
X361200Y90200D03*
X371950Y92500D03*
X364874Y98250D03*
X362803Y106035D03*
X357900Y99200D03*
X368600Y97500D03*
X357721Y91779D03*
X361200Y97500D03*
X365316Y108130D03*
X372700Y119663D03*
X370100Y119563D03*
X370000Y116563D03*
X362111Y127142D03*
X362120Y124153D03*
X359421Y127128D03*
Y124008D03*
X372821Y125628D03*
X370121Y125528D03*
X367321Y122528D03*
X368026Y137118D03*
X364700Y134000D03*
X367992Y133982D03*
X359300Y130000D03*
X367900Y152550D03*
X368000Y146500D03*
X361700Y143300D03*
X364886Y140268D03*
X368026D03*
Y143418D03*
X364621Y143328D03*
X361500Y149500D03*
X368026Y149718D03*
X368100Y165300D03*
X364600D03*
X367950Y159200D03*
X371157Y162320D03*
X371176Y158940D03*
X358477Y159300D03*
X361600Y159250D03*
X358500Y155700D03*
X371100Y168700D03*
X364600Y174800D03*
X361500Y175000D03*
Y168500D03*
X367906Y171458D03*
X364600Y171600D03*
X364607Y177103D03*
X370900Y171700D03*
X361200Y178500D03*
X372400Y179100D03*
X369021Y180128D03*
X372600Y181400D03*
X364792Y188743D03*
X364600Y186138D03*
X364895Y190941D03*
X369106Y191903D03*
X369200Y189100D03*
X361257Y193524D03*
Y190700D03*
X364947Y193141D03*
X372700Y213700D03*
X369450Y212040D03*
X358498Y210220D03*
X358382Y212427D03*
X372800Y221600D03*
X369580Y218800D03*
X357966Y217516D03*
X359827Y216341D03*
X383350Y83350D03*
X383450Y90500D03*
X387200D03*
X387100Y83500D03*
X375800D03*
Y90500D03*
X379500Y83302D03*
Y90600D03*
X381600Y119900D03*
X381900Y113000D03*
X382596Y108600D03*
X385600Y116500D03*
X385200Y113137D03*
X385721Y119528D03*
X385479Y125569D03*
X381500Y123200D03*
X381600Y126427D03*
X385523Y122532D03*
X386708Y137118D03*
X383567Y137096D03*
X380475Y137016D03*
X380443Y130102D03*
X374200Y136994D03*
X380398Y146568D03*
X383548D03*
X374200Y140144D03*
X380400Y152700D03*
X383575Y149603D03*
X380522Y149564D03*
X386853Y149640D03*
X377476Y149688D03*
X374200Y149494D03*
X374100Y159150D03*
X386800Y165300D03*
X380398Y165240D03*
X383781Y165235D03*
X386777Y159005D03*
X380500Y162025D03*
X383700Y162199D03*
X383500Y159000D03*
X374300Y155800D03*
X377500Y165240D03*
X384740Y180080D03*
X381720Y180220D03*
X381800Y183300D03*
X380540Y177370D03*
X383693Y171424D03*
X386600Y174900D03*
X380477Y171605D03*
X376830Y175640D03*
X381460Y195610D03*
X384390Y196470D03*
X381140Y187960D03*
X381280Y191550D03*
X384708Y188910D03*
X384600Y186100D03*
X373922Y193103D03*
X374000Y190350D03*
X379750Y213500D03*
X376300Y211000D03*
X382600Y222600D03*
X382750Y229000D03*
X379700Y219200D03*
X385947Y226500D03*
X385900Y218400D03*
X376300Y216200D03*
X390700Y89300D03*
X403726Y83826D03*
X403700Y90200D03*
X397300Y89168D03*
X400400Y92200D03*
Y98500D03*
X390750Y96500D03*
X394100Y91400D03*
Y99000D03*
X397100Y96600D03*
X393331Y118043D03*
X393351Y115107D03*
X397650Y115500D03*
X401749Y112418D03*
X401159Y119636D03*
X401353Y116562D03*
X396276Y120948D03*
X396251Y117999D03*
X396600Y112463D03*
X389700Y112363D03*
X398500Y125604D03*
X398512Y122815D03*
X401500Y125600D03*
X393482Y123982D03*
X396700Y128000D03*
X389914Y124536D03*
X397800Y130000D03*
X390100Y127600D03*
X390205Y133858D03*
X392998Y133968D03*
X396148D03*
X396321Y136987D03*
X402561Y137000D03*
X399298Y137118D03*
X392998D03*
X389848D03*
X402400Y140163D03*
X393000Y152663D03*
X402900Y149663D03*
X396148Y140268D03*
X399298D03*
X389848Y146568D03*
X393204Y146436D03*
X403080Y146931D03*
X399198Y146468D03*
X396192Y146444D03*
X392998Y149718D03*
X399198Y149618D03*
X396182Y149674D03*
X396200Y152763D03*
X396300Y162100D03*
X399300Y152863D03*
Y155963D03*
X392998Y165240D03*
X393028Y162059D03*
X393198Y158940D03*
X403078Y152922D03*
X402373Y155952D03*
X399298Y162090D03*
X402505Y159133D03*
X396148Y158940D03*
X399298D03*
X392599Y181686D03*
X400252Y182966D03*
X403600Y182400D03*
Y180200D03*
X402540Y171760D03*
X402600Y174611D03*
X396000Y179000D03*
X399385Y171686D03*
X396225D03*
X390025Y174672D03*
X393085Y171686D03*
Y174836D03*
X397100Y181000D03*
X400301Y186099D03*
X397805Y192061D03*
X392600Y190600D03*
X396200Y194700D03*
X392624Y184537D03*
X389500Y193600D03*
X397307Y186607D03*
X395600Y184100D03*
Y190300D03*
X392700Y193563D03*
X403022Y192094D03*
X402967Y195005D03*
X389484Y190442D03*
X389300Y187700D03*
X392100Y213700D03*
X395700Y213600D03*
X389100Y224000D03*
X399700Y225000D03*
Y216400D03*
X395600Y224400D03*
X395700Y217000D03*
X391950Y220800D03*
X389150Y230300D03*
X407500Y84000D03*
X407400Y91000D03*
X411300Y85600D03*
X414722Y90250D03*
X418300Y91300D03*
X418400Y98150D03*
X411000Y92100D03*
X414622Y98000D03*
X404529Y118507D03*
X405900Y121700D03*
X409110Y114910D03*
X405200Y115343D03*
X412462Y115713D03*
X409196Y118195D03*
X416904Y119591D03*
X413100Y121800D03*
X404900Y124600D03*
X416000Y135983D03*
X415000Y131400D03*
X408956Y130064D03*
X418500Y128200D03*
X415100Y127900D03*
X406200Y127400D03*
X416851Y122600D03*
X412600Y124100D03*
X412462Y126300D03*
X414900Y147000D03*
X417900Y146900D03*
X408800Y147000D03*
X411900Y146800D03*
X413300Y139100D03*
X413400Y142700D03*
X418000Y142500D03*
X406000Y150200D03*
X407500Y152100D03*
X410400Y152000D03*
X418439Y167118D03*
X414800Y162600D03*
X411800Y162700D03*
X414572Y165913D03*
X411356Y165732D03*
X407500Y157600D03*
X412900Y157800D03*
X407400Y154863D03*
X406100Y159500D03*
X415100Y158100D03*
X410272Y154794D03*
X416400Y155000D03*
X408600Y159600D03*
X411600D03*
X409300Y167163D03*
X404558Y154835D03*
X407100Y167429D03*
X418600Y182800D03*
X414960Y178130D03*
X414950Y181460D03*
X411260Y178090D03*
X411553Y181222D03*
X416400Y170300D03*
X413265Y170423D03*
X410620Y173300D03*
X415992Y189254D03*
Y186205D03*
X419097Y189563D03*
X416500Y195563D03*
X408242Y184624D03*
X405231Y184976D03*
X408200Y190500D03*
X408100Y193600D03*
X405000Y190700D03*
X412500Y194900D03*
X412100Y190400D03*
X411342Y185024D03*
X405800Y196700D03*
X412200Y192600D03*
X416900Y200100D03*
X408200Y226900D03*
X408100Y220500D03*
X404400Y228600D03*
Y222300D03*
X415600Y222700D03*
X415800Y215900D03*
X412050Y225100D03*
X412100Y218400D03*
X422078Y97678D03*
X422000Y91300D03*
X427560Y104770D03*
X429105Y106337D03*
X426800Y97850D03*
X429500Y93800D03*
X428100Y120000D03*
X424900Y121213D03*
X420600Y118300D03*
X420672Y120600D03*
X422042Y115224D03*
X424700Y115000D03*
X427900Y114300D03*
X428100Y116500D03*
X430302Y112098D03*
X419596Y113463D03*
X428255Y126236D03*
X425000Y135350D03*
X419500Y136400D03*
X430100Y131500D03*
X431700Y128300D03*
X423500Y128200D03*
X427000Y128050D03*
X423900Y131500D03*
X420942Y131324D03*
X422300Y126300D03*
X431504Y126061D03*
X427600Y143841D03*
X421500Y142400D03*
X426900Y147100D03*
X431100Y145500D03*
X424856Y142270D03*
X422400Y139000D03*
X420861Y149687D03*
Y146923D03*
X430694Y142275D03*
X428390Y139059D03*
X423945Y165221D03*
X421710Y167230D03*
X431130Y166660D03*
X428238Y167709D03*
X420804Y162659D03*
X420900Y160037D03*
X425500Y154737D03*
X428400D03*
X434500Y160037D03*
X430360Y181350D03*
X430340Y177620D03*
X423642Y181374D03*
X426970Y178310D03*
X425400Y170240D03*
X428500Y173120D03*
X422337Y170575D03*
X425427Y173113D03*
X419453Y173187D03*
X420922Y178117D03*
X423842Y178274D03*
X428431Y170264D03*
X432100Y190400D03*
X429100Y189696D03*
X426173Y190784D03*
X428830Y195379D03*
X422152Y189600D03*
X420800Y193100D03*
X421171Y196496D03*
X431270Y193425D03*
X425500Y186045D03*
X429933Y197283D03*
X420975Y211300D03*
X427900Y202800D03*
X424832Y200174D03*
X421811Y202603D03*
X421253Y199822D03*
X419550Y222700D03*
X419600Y216200D03*
X437400Y121600D03*
X442842Y120824D03*
X438700Y112900D03*
X438500Y116400D03*
X439400Y120100D03*
X434960Y114529D03*
X444242Y124324D03*
X435442Y124024D03*
X437800Y128100D03*
X434700Y128200D03*
X443400Y148900D03*
X437472Y152501D03*
X434834Y163817D03*
X439600Y153800D03*
X438742Y197224D03*
X435642Y194824D03*
X437921Y192956D03*
X459800Y118800D03*
X453000Y118700D03*
X459700Y129900D03*
X452200Y129800D03*
X463100Y133700D03*
X456000Y133500D03*
X460100Y123100D03*
X453000Y123300D03*
X463200Y126200D03*
X456500Y126100D03*
X461200Y167400D03*
X454200D03*
X464300Y181800D03*
X458000Y171100D03*
X451000D03*
X460000Y174900D03*
X453000D03*
X457400Y197000D03*
X450400D03*
X462500Y189000D03*
X460400Y193300D03*
X453400D03*
X459500Y200700D03*
X452500D03*
X473900Y178200D03*
X466900D03*
X471300Y181800D03*
X473100Y185500D03*
X466000D03*
X469500Y189000D03*
X504000Y12507D03*
X508700Y14607D03*
X511589Y30295D03*
X507839Y30362D03*
X506496Y272500D03*
X523453Y12360D03*
X511800Y12507D03*
X520700Y14807D03*
X518769Y22907D03*
X515484D03*
X525753Y30893D03*
X522733Y32832D03*
X511640Y255956D03*
X514137Y256089D03*
X522908Y255117D03*
X526715Y254700D03*
X511736Y273001D03*
X514900Y271350D03*
X522992Y270700D03*
X525845Y272863D03*
X517846Y262489D03*
X521131D03*
X528525Y12549D03*
X542100Y15107D03*
X530700Y15407D03*
X536485Y22907D03*
X533200D03*
X542407Y30882D03*
X532350Y30807D03*
X529120Y32575D03*
X530015Y255000D03*
X531775Y252231D03*
X541005Y254800D03*
X530900Y273000D03*
X534100Y270700D03*
X541500Y270900D03*
X535562Y262489D03*
X538847D03*
X550000Y12507D03*
X544860Y12407D03*
X552800Y14807D03*
X557745Y22907D03*
X554460D03*
X553079Y30712D03*
X549500Y31607D03*
X545928Y31047D03*
X544800Y255100D03*
X550200Y255500D03*
X551000Y252056D03*
X544292Y273128D03*
X548800Y271000D03*
X551937Y272789D03*
X555641Y262489D03*
X568555Y12407D03*
X561200Y12507D03*
X571600Y14207D03*
X564400Y14307D03*
X570852Y33204D03*
X569800Y29807D03*
X565091Y30815D03*
X561456Y30902D03*
X561419Y254850D03*
X565054Y254773D03*
X568327Y253348D03*
X571867Y254685D03*
X560600Y270300D03*
X564100Y271100D03*
X567800Y270500D03*
X570200Y273100D03*
X558926Y262489D03*
X587940Y12417D03*
X582655Y12407D03*
X579800Y14807D03*
X577824Y22907D03*
X574539D03*
X585179Y30867D03*
X581450Y30707D03*
X587700Y255300D03*
X579205Y254850D03*
X582200Y252206D03*
X587642D03*
X580200Y273000D03*
X582600Y270300D03*
X588036Y273089D03*
X588400Y270300D03*
X573357Y262489D03*
X576642D03*
X594600Y6707D03*
X601704Y22907D03*
X594400Y36207D03*
X589300Y33007D03*
X594600Y260000D03*
X591300Y255010D03*
X590837Y259889D03*
X598398Y260199D03*
X591342Y252206D03*
X594500Y265200D03*
X591500Y270100D03*
X591536Y273000D03*
X590700Y264833D03*
X598300Y265400D03*
X610952Y12307D03*
X616600D03*
X615852Y19807D03*
X615907Y24856D03*
X607300Y14507D03*
X616707Y15616D03*
X604989Y22907D03*
X612000Y17407D03*
X610944Y33333D03*
X607800Y30407D03*
X618900Y33290D03*
X615103Y30690D03*
X619382Y260089D03*
X615532Y259700D03*
X611706Y259387D03*
X606700Y255600D03*
X604074Y254394D03*
X609500Y254900D03*
X609937Y252106D03*
X615537Y264789D03*
X619100Y265300D03*
X611536Y264385D03*
X609896Y272889D03*
X608996Y270206D03*
X605100Y270100D03*
X605065Y272967D03*
X623532Y20007D03*
X623555Y25107D03*
X619607Y19807D03*
X627255Y25107D03*
X627231Y19907D03*
X630955Y25207D03*
X631000Y20107D03*
X634555Y25307D03*
X634757Y20207D03*
X619730Y24864D03*
X630432Y260100D03*
X626682Y260300D03*
X622933Y260189D03*
X634207Y260300D03*
X630455Y265400D03*
X634280Y265332D03*
X626651Y265489D03*
X622899Y265189D03*
X644193Y12907D03*
X648800Y12707D03*
X638400Y20607D03*
X638290Y25674D03*
X642246Y25807D03*
X642451Y20707D03*
X645300Y15507D03*
X648400Y15490D03*
X647000Y29607D03*
X649550Y30807D03*
X643700Y33290D03*
X644100Y30307D03*
X638032Y260342D03*
X642802Y252186D03*
X645920Y254130D03*
X635043Y252106D03*
X638900Y254809D03*
X638090Y265340D03*
X642937Y273089D03*
X646360Y271530D03*
X637288Y270100D03*
X637337Y272944D03*
X648948Y262489D03*
X644550Y267170D03*
X662359Y12379D03*
X659400Y25907D03*
Y20474D03*
X662192Y14874D03*
X663202Y25973D03*
X655602Y25223D03*
X663200Y20956D03*
X655700Y20225D03*
X662503Y33207D03*
X657900Y30690D03*
X664678Y30307D03*
X661708Y30699D03*
X659437Y246389D03*
X665500Y252189D03*
X659500Y274000D03*
X665100Y272700D03*
X652233Y262489D03*
X671290Y12457D03*
X665901Y12307D03*
X674320Y14219D03*
X666175Y14807D03*
X680580Y22807D03*
X677295D03*
X674400Y31307D03*
X671295Y33190D03*
X670200Y254700D03*
X673770Y254752D03*
X669700Y270900D03*
X672800Y272700D03*
X676113Y262489D03*
X679398D03*
X690102Y12502D03*
X684760Y12256D03*
X692200Y15357D03*
X682013Y14848D03*
X695029Y22853D03*
X693300Y30607D03*
X689624Y30383D03*
X685700Y30807D03*
X681900Y30907D03*
X682800Y254900D03*
X685382Y252200D03*
X688800Y254600D03*
X692250Y255700D03*
X682481Y270700D03*
X685100Y273100D03*
X689700Y270800D03*
X692537Y272989D03*
X696192Y262489D03*
X709000Y12407D03*
X702000Y12607D03*
X705031Y14515D03*
X698277Y22855D03*
X708900Y30407D03*
X704430Y33313D03*
X701800Y30807D03*
X701649Y255049D03*
X704178Y252189D03*
X707800Y255000D03*
X711400Y255072D03*
X701300Y270777D03*
X704277Y272989D03*
X709400Y272600D03*
X699477Y262489D03*
X723586Y14080D03*
X712182Y14124D03*
X720100Y14707D03*
X718375Y22907D03*
X715090D03*
X727000Y30407D03*
X723500Y29907D03*
X721747Y32954D03*
X712400Y30807D03*
X721500Y255000D03*
X724374Y254515D03*
X712200Y270500D03*
X722400Y270800D03*
X725300Y272800D03*
X717452Y262489D03*
X720737D03*
X715900Y270000D03*
X742200Y12407D03*
X728010Y12857D03*
X739000Y14407D03*
X731169Y14584D03*
X736091Y23607D03*
X732806D03*
X742100Y33007D03*
X740200Y29907D03*
X730500D03*
X730400Y255400D03*
X732200Y252200D03*
X741560Y255000D03*
X730400Y272850D03*
X732740Y270200D03*
X741200Y270500D03*
X735168Y262489D03*
X738453D03*
X744900Y20500D03*
X745000Y23000D03*
X747441Y33007D03*
X744437Y252189D03*
X744200Y272600D03*
X753000Y272100D03*
G54D17*
X42717Y191732D03*
G54D19*
X144000Y67875D03*
Y147125D03*
X276811Y263386D03*
X296811D03*
X457913Y45276D03*
X477913D03*
G54D14*
X13000Y137000D03*
Y141500D03*
X13100Y150600D03*
X13000Y146000D03*
X45500Y118000D03*
X76200Y187200D03*
X86500Y177500D03*
X90700Y177050D03*
X122250Y228750D03*
Y233000D03*
Y237300D03*
Y241500D03*
X133941Y208863D03*
X131003Y205766D03*
X138100Y208100D03*
X136500Y272500D03*
X158700Y213800D03*
X309100Y206800D03*
X315400Y110800D03*
X311600D03*
X322691Y136023D03*
X323550Y142104D03*
X319401Y149354D03*
X317698Y152311D03*
X315384Y166733D03*
X324953Y161722D03*
X323165Y171937D03*
X324436Y175705D03*
X326399Y169401D03*
X319942Y180524D03*
X320029Y184300D03*
X318700Y207800D03*
X311600Y207600D03*
X328000Y97100D03*
X334850Y96900D03*
X335500Y91600D03*
X339500Y102000D03*
X332600Y101400D03*
X333551Y115090D03*
X333416Y108899D03*
X341309Y135651D03*
X329693Y134428D03*
X331290Y125810D03*
X330870Y130540D03*
X336190Y141970D03*
X330796Y146221D03*
X333742Y161624D03*
X332185Y153806D03*
X334470Y164760D03*
X335400Y169600D03*
X333842Y177224D03*
X332300Y173900D03*
X339875Y177303D03*
X334715Y180900D03*
X329028Y199931D03*
X344523Y98477D03*
X344500Y94000D03*
X347230Y100190D03*
X355175Y108212D03*
X348076Y108910D03*
X354333Y125665D03*
X343000Y124000D03*
X342880Y146180D03*
X350800Y138300D03*
X355342Y143424D03*
X348743Y149100D03*
X342716Y161593D03*
X345562Y178700D03*
X349751Y187241D03*
X356800Y191000D03*
X361141Y104099D03*
X369997Y113706D03*
X358000Y115500D03*
X364600Y137063D03*
X367221Y125428D03*
X370000Y122563D03*
X367121Y128628D03*
X362111Y130128D03*
X361726Y140268D03*
X361700Y146549D03*
X361400Y187600D03*
X368455Y196455D03*
X371299Y196008D03*
X361300Y184500D03*
X369009Y186191D03*
X359750Y208390D03*
X359910Y214100D03*
X371100Y199500D03*
X365250Y208600D03*
X369580Y215400D03*
X377818Y115008D03*
X377800Y124163D03*
X384650Y183170D03*
X376742Y181524D03*
X376800Y193500D03*
X376900Y196600D03*
X380510Y185500D03*
X384684Y191950D03*
X376300Y213700D03*
X382471Y199843D03*
X385900Y222600D03*
X382700Y226000D03*
X379700Y216500D03*
X372950Y217400D03*
X390683Y108042D03*
X400700Y108800D03*
X393653Y121122D03*
X401500Y122600D03*
X401256Y128755D03*
X395573Y175400D03*
X400352Y180171D03*
X402962Y189014D03*
X397728Y189053D03*
X389200Y227400D03*
X392000Y217200D03*
X395700Y220600D03*
X399800D03*
X414672Y94500D03*
X417800Y100400D03*
X418300Y94800D03*
X407550Y100196D03*
X409110Y120910D03*
X412100Y135600D03*
X417753Y131322D03*
X404400Y128900D03*
X415700Y143100D03*
X410302Y141864D03*
X406042Y147025D03*
X415100Y149800D03*
X407399Y142561D03*
X408837Y149809D03*
X413314Y154908D03*
X416315Y183219D03*
X412000Y187500D03*
X405102Y187874D03*
X408200Y223800D03*
X412000Y222000D03*
X404400Y225300D03*
X422050Y94800D03*
X424982Y126500D03*
X432542Y136898D03*
X426982Y131334D03*
X423496Y144000D03*
X428363Y141756D03*
X426000Y167370D03*
X430542Y160753D03*
X430600Y164513D03*
X422363Y154700D03*
X423966Y190846D03*
X423800Y196500D03*
X433842Y197021D03*
X421848Y186550D03*
X426311Y204399D03*
X444578Y106201D03*
X442378Y106198D03*
X440178Y106200D03*
X443443Y144757D03*
X437398Y146257D03*
X435004Y142110D03*
G54D23*
X305900Y121151D03*
X311200Y114800D03*
X311410Y118110D03*
X312000Y122600D03*
X312917Y133440D03*
X312829Y181940D03*
X345837Y199887D03*
G54D12*
X14000Y104500D03*
X14400Y98000D03*
X14000Y109500D03*
X14500Y198000D03*
X17301Y212401D03*
X4500Y228900D03*
X4600Y223100D03*
X17300Y218307D03*
X10000Y229500D03*
X16400Y224212D03*
X4500Y234800D03*
X4400Y245100D03*
X16118Y230118D03*
X10194Y243106D03*
X9500Y234200D03*
X16899Y241929D03*
X16300Y236023D03*
X4400Y256700D03*
X10190Y258510D03*
X10194Y254917D03*
X10190Y246699D03*
X16899Y247834D03*
Y253740D03*
Y259645D03*
X5000Y275000D03*
X12600Y266900D03*
X7600Y268100D03*
X16899Y265551D03*
X15300Y285800D03*
X4900Y285700D03*
X23400Y81550D03*
X25000Y77300D03*
X32800Y120400D03*
X25800Y120300D03*
X29200D03*
X30000Y196200D03*
X21900Y205400D03*
X31500Y207500D03*
X25200Y286000D03*
X40500Y127700D03*
X38500Y148000D03*
X48500D03*
X41000Y152300D03*
Y143300D03*
X46000D03*
Y152300D03*
X43500Y148000D03*
Y138500D03*
X48500D03*
X38500D03*
X45800Y158100D03*
X34800Y198800D03*
Y203700D03*
X37600Y212700D03*
Y207800D03*
X34500Y216000D03*
X40400Y217100D03*
X40700Y224000D03*
X40200Y238300D03*
Y231300D03*
Y245300D03*
X40500Y260000D03*
X40600Y252500D03*
X52500Y96500D03*
Y106500D03*
X57500Y96500D03*
X60000Y101500D03*
X50000D03*
X55000D03*
X57500Y106500D03*
X60000Y111300D03*
X50000D03*
X55000D03*
X50500Y160000D03*
X54700Y192200D03*
X52700Y184800D03*
X62800Y184300D03*
X57600Y214200D03*
X74000Y37642D03*
X66500D03*
X78300Y64300D03*
X72137Y210237D03*
X79500Y230000D03*
X78700Y259800D03*
X67600Y255800D03*
X66300Y259300D03*
X67000Y263200D03*
X82211Y37747D03*
X89862Y37849D03*
X89400Y58200D03*
X83600Y57600D03*
X95500Y93500D03*
X94000Y137500D03*
Y133000D03*
X84500Y230000D03*
X89500D03*
X84500Y225000D03*
Y235000D03*
X91400Y270300D03*
X98500Y37642D03*
X105794Y37692D03*
X104400Y57700D03*
X96800Y53300D03*
X99500Y91500D03*
Y96000D03*
X104000Y92000D03*
Y96500D03*
X105775Y137349D03*
X103175Y134050D03*
X98500Y137500D03*
X109000Y134050D03*
X98500Y133000D03*
X95700Y197200D03*
X99600Y225700D03*
X99328Y235370D03*
X109000Y231400D03*
X113605Y37665D03*
X121500Y37642D03*
X121400Y60100D03*
X114800Y60700D03*
X114500Y134050D03*
X120500Y139000D03*
X125000Y178000D03*
X119760Y191419D03*
X115760D03*
X123760D03*
X129336Y37652D03*
X137300Y37642D03*
X136400Y60600D03*
X130400D03*
X136500Y101523D03*
X136770Y113000D03*
X136500Y126300D03*
X132700Y158600D03*
X153088Y37653D03*
X145070Y37642D03*
X143700Y54503D03*
X154615Y54500D03*
X152811Y84300D03*
X157175Y115462D03*
X150670Y112100D03*
Y122300D03*
X150500Y183000D03*
X157000Y169194D03*
X168791Y37689D03*
X160898Y37704D03*
X169600Y53000D03*
X159957Y51932D03*
X167500Y68000D03*
X158105Y96775D03*
X171800Y126600D03*
X162900Y152200D03*
X167602Y160684D03*
X169800Y181448D03*
X165700Y203400D03*
X162000Y226000D03*
X167000D03*
Y221500D03*
X162000D03*
Y230500D03*
X167000D03*
X162000Y235000D03*
X176640Y37699D03*
X184500Y37700D03*
X185000Y51600D03*
X175758Y52879D03*
X184300Y78500D03*
X177200Y130575D03*
X187597Y133697D03*
X176400Y175700D03*
X185546Y192509D03*
X180546D03*
X175546D03*
X177500Y209500D03*
X176800Y241600D03*
X186500Y276500D03*
Y281000D03*
X192400Y37642D03*
X200300D03*
X191700Y52100D03*
X201500Y54500D03*
X196900Y68700D03*
X198500Y83800D03*
X193485Y83724D03*
X202500Y97000D03*
X188363Y116137D03*
X201252Y137766D03*
X192237Y147300D03*
X199900Y154200D03*
X200900Y177000D03*
X202800Y191400D03*
X196000Y186897D03*
X191400Y206100D03*
X203100Y252900D03*
X191100Y276600D03*
X190900Y280800D03*
X207600Y37642D03*
X216085Y37649D03*
X210900Y57600D03*
X213558Y98500D03*
X205689Y112879D03*
X205850Y118175D03*
X210100Y135800D03*
X213850Y179850D03*
X205920Y221550D03*
X211900Y253000D03*
X207500D03*
X212400Y281200D03*
X217000Y281000D03*
X212500Y277000D03*
X208000D03*
X223868Y37686D03*
X231780Y37691D03*
X229036Y83000D03*
X231562Y143827D03*
X231611Y138336D03*
X226452Y147300D03*
X233350Y180700D03*
X232225Y193275D03*
X233500Y258958D03*
X228000Y259000D03*
X239599Y37673D03*
X247500Y37642D03*
X238800Y45300D03*
X240200Y59275D03*
X247500Y60000D03*
X244463Y130655D03*
X242950Y155800D03*
X236477Y179357D03*
X239300Y196800D03*
X236861Y184967D03*
X248300Y213500D03*
X248000Y259000D03*
X238500D03*
X243000D03*
X261900Y44900D03*
X255000Y37642D03*
X263100Y37700D03*
X264700Y59400D03*
X256200Y59200D03*
X264189Y98252D03*
X257000Y213500D03*
X252700D03*
X252500Y259000D03*
X271000Y37800D03*
X278800Y37700D03*
X274000Y55800D03*
X268928Y112625D03*
X268895Y107350D03*
X268300Y141869D03*
X269772Y188274D03*
X274700Y222100D03*
X286900Y37800D03*
X294500Y37900D03*
X292500Y60500D03*
X284000Y55800D03*
X288700Y71100D03*
X292100D03*
X295300Y66200D03*
X285100Y129510D03*
X281500Y142100D03*
X295900Y154200D03*
X287700Y211900D03*
X295300Y238100D03*
X285000Y261700D03*
X310348Y37900D03*
X302600Y37800D03*
X302400Y59500D03*
X306100Y90600D03*
X311000Y141731D03*
X297250Y163700D03*
X311242Y158732D03*
X305290Y187836D03*
X301320Y191060D03*
X310500Y195600D03*
X308200D03*
X326096Y37900D03*
X318048Y37700D03*
X311598Y57522D03*
X322548Y58300D03*
X323882Y71643D03*
X318882D03*
X321300Y88200D03*
X325350Y114500D03*
X326313Y122380D03*
X311460Y172078D03*
X323800Y192150D03*
X323789Y188117D03*
X326500Y187900D03*
X311900Y188070D03*
X319500Y212100D03*
X315585Y207787D03*
X324100Y208000D03*
X325200Y221700D03*
X319400Y216200D03*
X313600Y237700D03*
X321400D03*
X322000Y264300D03*
X333700Y38000D03*
X328300Y58200D03*
X337000Y74202D03*
X328882Y71643D03*
X330470Y112515D03*
X330910Y115010D03*
X338421Y153802D03*
X326831Y196119D03*
X337670Y213520D03*
X332974Y210874D03*
X339800Y207400D03*
X330200Y216800D03*
X336000Y219750D03*
X333036Y231910D03*
X327100Y237100D03*
X353100Y56151D03*
X346600Y121100D03*
X355460Y149510D03*
X355413Y156050D03*
X351700Y167300D03*
X355300Y174600D03*
X350000Y177700D03*
X353321Y180128D03*
X350409Y199755D03*
X354700Y199900D03*
X363583Y37642D03*
X368721Y108528D03*
X365721Y115528D03*
X366400Y112200D03*
X371176Y136890D03*
X364700Y152713D03*
X368100Y162200D03*
X358342Y165324D03*
X358576Y162090D03*
X368000Y168500D03*
X361292Y181409D03*
X365800Y264900D03*
X362400D03*
X369300D03*
X375400Y37700D03*
X374200Y143294D03*
X387000Y155850D03*
X380500Y168500D03*
X383548Y168390D03*
X376800Y178600D03*
X380000Y263461D03*
X383500D03*
X376500D03*
X393561Y127130D03*
X396148Y155790D03*
X393208D03*
X399298Y165240D03*
X395641Y188045D03*
X393000Y236200D03*
X397400Y239700D03*
X389500Y275300D03*
X416922Y116613D03*
X405990Y144251D03*
X409096Y143963D03*
X410100Y157700D03*
X408900Y162463D03*
X410408Y170261D03*
X405100Y178500D03*
X407552Y170424D03*
X415700Y219200D03*
X405700Y246500D03*
X430500Y17000D03*
X427500Y112091D03*
X425200Y118823D03*
X430342Y119724D03*
X426900Y160040D03*
X419340Y170500D03*
X434482Y177021D03*
X428400Y185900D03*
X419600Y219200D03*
X423900Y257500D03*
X444783Y28451D03*
X439276Y159645D03*
X443800Y246100D03*
X445300Y274400D03*
X451000Y257413D03*
X456300Y275300D03*
X474000Y9000D03*
X467200Y4400D03*
X480400Y154050D03*
X467100Y154200D03*
X477000Y154050D03*
X470100Y154200D03*
X473500Y154050D03*
X467700Y245500D03*
X481500Y8900D03*
X489600Y8800D03*
X483800Y154050D03*
X487200Y154100D03*
X497100Y8800D03*
X506800Y12907D03*
X508700Y17207D03*
X506500Y32807D03*
X502000Y89000D03*
X511200Y183400D03*
X500900D03*
X505200Y215000D03*
X514360Y12417D03*
X526000Y12507D03*
X519426Y12318D03*
X522311Y16720D03*
X514300Y20507D03*
X519623Y20457D03*
X522700Y30007D03*
X513005Y32412D03*
X519400Y33340D03*
X526700Y33207D03*
X525740Y88960D03*
X524700Y119500D03*
X515000Y119270D03*
X524700Y145041D03*
X526600Y183500D03*
X513100Y234500D03*
X516500D03*
X537964Y12317D03*
X532500Y13407D03*
X541114Y12307D03*
X528219Y15096D03*
X532472Y20515D03*
X537410Y20584D03*
X529000Y30007D03*
X541950Y33340D03*
X532542Y33307D03*
X537200Y33207D03*
X531500Y219500D03*
X541500Y234900D03*
X547500Y12507D03*
X553720Y12297D03*
X550234Y14997D03*
X553797Y20496D03*
X549500Y29107D03*
X553250Y33207D03*
X547306Y33134D03*
X551800Y69600D03*
X548400Y69700D03*
X555199D03*
X556500Y89000D03*
X546349Y89512D03*
X552100Y136000D03*
X557100D03*
X544954Y183600D03*
X551700Y209800D03*
X550400Y222285D03*
X558448Y12407D03*
X566040Y12317D03*
X566000Y16507D03*
X572200Y28707D03*
X558500Y20507D03*
X573200Y19907D03*
X565470Y33287D03*
X573242Y32462D03*
X560635Y33264D03*
X561999Y69700D03*
X558599D03*
X570715Y89100D03*
X572100Y136000D03*
X567100D03*
X562000Y127800D03*
X562100Y136000D03*
X562000Y144900D03*
X558915Y183603D03*
X569200Y223600D03*
X573470Y12347D03*
X578620Y12357D03*
X585280Y12267D03*
X583700Y28207D03*
X578600Y20307D03*
X579100Y33207D03*
X585550Y33340D03*
X582254Y183313D03*
X590000Y14007D03*
X594500Y4007D03*
X600896Y12407D03*
X601000Y20507D03*
X590500Y30507D03*
X594200Y33607D03*
X600360Y33287D03*
X596845Y89624D03*
X599300Y119270D03*
X588800Y145000D03*
X599200D03*
X590975Y183275D03*
X588800Y205900D03*
X603964Y210400D03*
X600900Y230200D03*
X598814Y240095D03*
X605700Y12407D03*
X614700Y14107D03*
X610800Y14807D03*
X605728Y20518D03*
X615951Y22356D03*
X610500Y30507D03*
X615044Y33190D03*
X607544Y33340D03*
X618877Y30790D03*
X617700Y125500D03*
X615700Y230200D03*
X615100Y238900D03*
X633500Y12406D03*
X624000D03*
X634757Y22707D03*
X623480Y22564D03*
X631007Y22707D03*
X619700Y22307D03*
X627257Y22407D03*
X624100Y33190D03*
X633449D03*
X630000Y55300D03*
X627500Y104900D03*
X620000Y112575D03*
X623400Y230100D03*
X623900Y239600D03*
X641745Y12367D03*
X645200Y27707D03*
X646800Y17607D03*
X642257Y23307D03*
X638507Y23183D03*
X650200Y33307D03*
X641900Y31507D03*
X646000Y46007D03*
X640000D03*
X640500Y55000D03*
X639500Y136490D03*
X648500Y162600D03*
X657897Y12504D03*
X651316Y12360D03*
X664212Y16356D03*
X663300Y23454D03*
X662916Y28457D03*
X655592Y22723D03*
X659400Y23207D03*
X657900Y33190D03*
X655133Y55833D03*
X654500Y46107D03*
X653000Y93000D03*
X650726Y125724D03*
X664212Y147993D03*
X661600Y156700D03*
X654100Y221800D03*
X675990Y12357D03*
X669600Y17907D03*
X676600Y20307D03*
X671500Y15007D03*
X671900Y30707D03*
X675970Y33267D03*
X678400Y114500D03*
X668411Y148089D03*
X678500Y141500D03*
X667061Y175239D03*
X676200Y181600D03*
X687602Y12439D03*
X694200Y13507D03*
X681280Y12457D03*
X684500Y15507D03*
X689595Y27883D03*
X685400Y28307D03*
X681700Y20507D03*
X694205Y20302D03*
X693700Y33107D03*
X681280Y33340D03*
X687900Y33327D03*
X693500Y148000D03*
X690000Y159000D03*
X694500D03*
X684700Y179800D03*
X694600Y229800D03*
X699503Y12482D03*
X706360Y12397D03*
X705604Y16949D03*
X710813Y28796D03*
X699104Y20495D03*
X707157Y33333D03*
X700940Y33340D03*
X700089Y91411D03*
X701600Y104900D03*
X701400Y98400D03*
X698000Y181500D03*
X704700Y183800D03*
X710200Y201700D03*
X714000Y12407D03*
X719110Y12347D03*
X725530Y12507D03*
X714100Y20607D03*
X719220Y20553D03*
X721074Y30514D03*
X718350Y33107D03*
X712450Y33340D03*
X725653Y32654D03*
X725632Y49600D03*
X721950Y51950D03*
X722000Y74500D03*
X717000D03*
X715000Y80300D03*
X714500Y85500D03*
X715700Y124200D03*
X727187Y140000D03*
X717000Y187500D03*
X715500Y205837D03*
X737300Y12307D03*
X732110Y12267D03*
X728500Y15507D03*
X742100Y28107D03*
X732000Y20307D03*
X736748D03*
X728500Y27907D03*
X733474Y33340D03*
X738487Y33094D03*
X739500Y75500D03*
X738000Y65700D03*
X738500Y90000D03*
X731340Y82515D03*
X739500Y114900D03*
X741104Y133763D03*
X736900Y162300D03*
X729500D03*
X733400D03*
X737000Y188315D03*
X734000Y205000D03*
X745100Y12256D03*
X744800Y33007D03*
X752500Y49007D03*
X756000Y106000D03*
X758176Y135024D03*
X745104Y129763D03*
X749104Y133763D03*
X745104D03*
X752191Y146613D03*
X745104Y137763D03*
X747000Y162000D03*
X750500D03*
X746000Y182300D03*
X764500Y84800D03*
X760400Y88700D03*
X768100Y89000D03*
X761300Y95700D03*
X768500Y114000D03*
X763600Y168000D03*
X764000Y188000D03*
Y197500D03*
Y192810D03*
Y202310D03*
X769500Y234500D03*
X769400Y252700D03*
X785500Y8000D03*
X784000Y31000D03*
X781500Y51000D03*
X777000Y93100D03*
X774300Y102500D03*
X778500D03*
Y107000D03*
X774300D03*
X783000Y113000D03*
Y118500D03*
Y123000D03*
X779000Y142000D03*
X788515Y144060D03*
X784515D03*
X796515D03*
X792515D03*
X800515D03*
Y148060D03*
X796515D03*
X792515D03*
X810500Y196500D03*
Y192300D03*
X809200Y209500D03*
Y213700D03*
Y218400D03*
X809100Y228600D03*
Y224400D03*
X808700Y238300D03*
Y234100D03*
Y242900D03*
X809500Y251500D03*
Y257000D03*
X808700Y247100D03*
X809700Y285900D03*
X820500Y6500D03*
X821900Y273100D03*
X821600Y285500D03*
G54D31*
X804032Y27032D03*
Y67032D03*
G54D29*
X350197Y231103D03*
G54D11*
X11500Y68500D03*
X12000Y279000D03*
X816000Y280000D03*
G54D16*
X45669Y77185D03*
Y172460D03*
G54D21*
X200197Y282677D03*
X298622D03*
G54D10*
X-19686Y15748D03*
Y573228D03*
X846455Y15748D03*
Y573228D03*
G54D25*
X315613Y100850D03*
X339280Y127380D03*
X431188Y116105D03*
X434700Y131800D03*
G54D26*
X325300Y112300D03*
X319252Y140949D03*
X324200Y157800D03*
X311417Y153821D03*
X341300Y169600D03*
X332100Y185600D03*
X338000Y185700D03*
X335000Y185500D03*
X332800Y187700D03*
X358500Y137000D03*
X385750Y128517D03*
X380400Y133928D03*
X387000Y143280D03*
X380398Y143418D03*
X383395Y143306D03*
X399452Y133964D03*
X389380Y130100D03*
X389721Y143320D03*
X393000Y140268D03*
X403132Y144374D03*
X405500Y131063D03*
X417900Y178363D03*
X431620Y154620D03*
X421697Y174049D03*
X439275Y124197D03*
X456200Y118900D03*
Y129600D03*
X459700Y133600D03*
X459800Y126200D03*
X456500Y123000D03*
X457700Y167400D03*
X456500Y174900D03*
X454500Y171100D03*
X456900Y193300D03*
X453900Y197000D03*
X456000Y200700D03*
X470400Y178200D03*
X467800Y181800D03*
X469600Y185500D03*
X466000Y189000D03*
G54D27*
X322010Y118573D03*
X323007Y127672D03*
X338048Y196250D03*
X342029Y196427D03*
X349600Y126700D03*
X342760Y187810D03*
X371900Y89000D03*
X368600Y94100D03*
X365000Y94700D03*
X357721Y95100D03*
X360900Y94200D03*
X359942Y110924D03*
X375800Y87000D03*
X383450Y86900D03*
X387200D03*
X379500D03*
X379526Y106396D03*
X381950Y100950D03*
X381550Y117400D03*
X377800Y112063D03*
X386561Y108812D03*
X377713Y121061D03*
X386777Y162155D03*
X377500Y156000D03*
X397300Y93100D03*
X390650Y93000D03*
X394100Y94900D03*
X400400Y95000D03*
X399300Y168400D03*
X393077Y168455D03*
X392596Y187541D03*
X414300Y85600D03*
X403800Y87000D03*
X407400Y87400D03*
X411000Y88900D03*
X417785Y162622D03*
X406000Y162663D03*
X408158Y178666D03*
X418800Y196700D03*
X416139Y192007D03*
X419499Y139064D03*
X423910Y175700D03*
X432712Y172469D03*
X435453Y167560D03*
X435105Y181207D03*
X435453Y185397D03*
X507817Y252248D03*
X511200Y258900D03*
X509244Y272796D03*
X516600Y252200D03*
X521800Y252875D03*
X513776Y258563D03*
X516727Y273122D03*
X521790Y273140D03*
X517100Y265100D03*
X521987D03*
X532900Y255300D03*
X535098Y252600D03*
X540900Y252300D03*
X527400Y252100D03*
X529300Y271000D03*
X528330Y273140D03*
X539937Y272989D03*
X539505Y265100D03*
X534905Y273097D03*
X534700Y265100D03*
X552800Y255300D03*
X545500Y252600D03*
X553485Y252332D03*
X546200Y271000D03*
X554500Y264900D03*
X546900Y273100D03*
X554434Y272914D03*
X560555Y252503D03*
X563376Y256627D03*
X566151Y252115D03*
X572150Y252200D03*
X570200Y269700D03*
X559600Y272900D03*
X572155Y264900D03*
X565700Y273050D03*
X559700Y264900D03*
X572700Y273100D03*
X582300Y254900D03*
X578800Y252200D03*
X577450Y264900D03*
X580107Y270501D03*
X577636Y272947D03*
X603187Y252056D03*
X589500Y257100D03*
X589900Y268133D03*
X602450Y272900D03*
X598418Y262699D03*
X590322Y262361D03*
X594559Y262559D03*
X595386Y272932D03*
X608700Y257300D03*
X611845Y253723D03*
X611593Y261885D03*
X606200Y267800D03*
X615430Y262213D03*
X612393Y273026D03*
X619180Y262689D03*
X629937Y272990D03*
X630457Y262832D03*
X626680Y262989D03*
X634280Y262832D03*
X620437Y272990D03*
X622930Y262689D03*
X643020Y254710D03*
X647800Y252300D03*
X635197Y254602D03*
X638893Y252206D03*
X644090Y270420D03*
X648200Y265300D03*
X637987Y262842D03*
X639500Y268800D03*
X648291Y273140D03*
X665300Y254700D03*
X661200Y248500D03*
X653600Y252130D03*
X664500Y270000D03*
X653000Y264900D03*
X661600Y272300D03*
X653041Y272989D03*
X669930Y252150D03*
X674636Y252406D03*
X680600Y265000D03*
X675400D03*
X668000Y272890D03*
X680400Y273100D03*
X675400D03*
X690000Y256800D03*
X685390Y254900D03*
X688720Y252090D03*
X693860Y252210D03*
X681900Y252500D03*
X691900Y269300D03*
X683100Y268000D03*
X695500Y265000D03*
Y273100D03*
X687682Y272889D03*
X704137Y254796D03*
X699800Y252230D03*
X701704Y257549D03*
X707490Y252310D03*
X706000Y270500D03*
X700200Y264900D03*
X700300Y273100D03*
X706900Y273000D03*
X712350Y252640D03*
X725950Y252573D03*
X721395Y252175D03*
X721600Y257500D03*
X716737Y252189D03*
X716795Y265000D03*
X721400D03*
X721395Y273100D03*
X713100Y273000D03*
X716737Y272989D03*
X730300Y257900D03*
X734937Y253100D03*
X739750Y252800D03*
X729860Y269810D03*
X734200Y265100D03*
X739111Y264962D03*
X739838Y272813D03*
X727800Y272800D03*
X734510Y273110D03*
X744100Y254800D03*
X749000Y252200D03*
X746737Y272889D03*
G54D28*
X320321Y130528D03*
X351342Y114158D03*
X351000Y111700D03*
X351950Y214800D03*
X346500Y208350D03*
X345500Y213000D03*
X353792Y208466D03*
X355860Y216690D03*
X345300Y216700D03*
X359222Y197700D03*
X412500Y197300D03*
X416353Y207249D03*
X425642Y209524D03*
X445000Y194500D03*
X443100Y195900D03*
X443000Y192700D03*
X436957Y209867D03*
G54D30*
X384810Y208530D03*
X384644Y205994D03*
X392382Y102149D03*
X400400Y209400D03*
X398500Y208000D03*
X412650Y100197D03*
X434021Y100128D03*
%LPC*%
G75*
G54D32*
G01X10636Y-27865D02*
G02I-12000J0D01*
G01X14636D02*
X-17364D01*
G01X5486D02*
G02I-6850J0D01*
G01X-1364Y-43865D02*
Y-11865D01*
G01X14636Y-43865D02*
Y-123865D01*
G01D02*
X1309236D01*
G01X14636Y-79365D02*
X1309236D01*
G01X14636Y-43865D02*
X1309236D01*
G01X521736D02*
Y-123865D01*
G01X659236Y-43865D02*
Y-123865D01*
G01X774236Y-43865D02*
Y-123865D01*
G01X941736Y-43865D02*
Y-123865D01*
G01X1111736Y-43865D02*
Y-123865D01*
G01X1309236Y-43865D02*
Y-123865D01*
G01X1341236Y-27865D02*
X1309236D01*
G01X1337236D02*
G02I-12000J0D01*
G01X1332086D02*
G02I-6850J0D01*
G01X1325236Y-43865D02*
Y-11865D01*
G54D33*
G01X70851Y-113865D02*
Y-96365D01*
G01X80021D02*
Y-113865D01*
G01Y-105115D02*
X70851D01*
G01X92936Y-113865D02*
X91626Y-113573D01*
X90316Y-112407D01*
X89442Y-110365D01*
X89006Y-108032D01*
X89442Y-105698D01*
X90316Y-103657D01*
X91626Y-102490D01*
X92936Y-102199D01*
X94246Y-102490D01*
X95556Y-103657D01*
X96429Y-105698D01*
X96648Y-108032D01*
X96429Y-110365D01*
X95556Y-112407D01*
X94246Y-113573D01*
X92936Y-113865D01*
G01X106724D02*
Y-102199D01*
G01Y-105115D02*
X107598Y-103657D01*
X108908Y-102490D01*
X110654Y-102199D01*
X112182Y-102490D01*
X113493Y-103657D01*
X114148Y-105698D01*
Y-113865D01*
G01X124661Y-105990D02*
X131648D01*
X130993Y-103948D01*
X129901Y-102782D01*
X128373Y-102199D01*
X126844Y-102490D01*
X125534Y-103365D01*
X124661Y-105407D01*
X124224Y-107157D01*
Y-108907D01*
X124661Y-110657D01*
X125753Y-112407D01*
X127063Y-113573D01*
X128591Y-113865D01*
X130119Y-113282D01*
X131648Y-111532D01*
G01X140851Y-119115D02*
X142161Y-119698D01*
X143908Y-119115D01*
X144999Y-117949D01*
X145873Y-116490D01*
X147182Y-111824D01*
X150021Y-102199D01*
G01X143034D02*
X147182Y-111824D01*
G01X182182Y-104532D02*
X183056Y-103657D01*
X183711Y-102199D01*
X184148Y-100156D01*
X183711Y-98407D01*
X182838Y-97240D01*
X181309Y-96365D01*
X175414D01*
Y-113865D01*
X182619D01*
X184148Y-112699D01*
X185021Y-110948D01*
X185458Y-108907D01*
X185021Y-106865D01*
X183711Y-105115D01*
X182182Y-104532D01*
X175414D01*
G01X201866Y-113865D02*
Y-102199D01*
G01Y-104240D02*
X200993Y-103074D01*
X199682Y-102490D01*
X198154Y-102199D01*
X196626Y-102782D01*
X195316Y-103948D01*
X194442Y-105698D01*
X194006Y-108032D01*
X194442Y-110365D01*
X195316Y-112115D01*
X196626Y-113282D01*
X198154Y-113865D01*
X199682Y-113573D01*
X200993Y-112699D01*
X201866Y-111532D01*
G01X219366Y-96365D02*
Y-113865D01*
G01Y-111241D02*
X218493Y-112699D01*
X217182Y-113573D01*
X215654Y-113865D01*
X213908Y-113282D01*
X212598Y-111824D01*
X211724Y-110074D01*
X211506Y-108032D01*
X211724Y-105990D01*
X212598Y-104240D01*
X213908Y-102782D01*
X215654Y-102199D01*
X217182Y-102490D01*
X218274Y-103074D01*
X219366Y-104240D01*
G01X229879Y-118240D02*
X231408Y-119407D01*
X233154Y-119698D01*
X234682Y-119407D01*
X235993Y-117949D01*
X236866Y-115907D01*
Y-102199D01*
G01Y-104532D02*
X235993Y-103365D01*
X234682Y-102490D01*
X233154Y-102199D01*
X231408Y-102782D01*
X230316Y-103948D01*
X229442Y-105990D01*
X229006Y-108032D01*
X229224Y-109782D01*
X230098Y-111824D01*
X231408Y-113282D01*
X233154Y-113865D01*
X234464Y-113573D01*
X235993Y-112407D01*
X236866Y-111241D01*
G01X247161Y-105990D02*
X254148D01*
X253493Y-103948D01*
X252401Y-102782D01*
X250873Y-102199D01*
X249344Y-102490D01*
X248034Y-103365D01*
X247161Y-105407D01*
X246724Y-107157D01*
Y-108907D01*
X247161Y-110657D01*
X248253Y-112407D01*
X249563Y-113573D01*
X251091Y-113865D01*
X252619Y-113282D01*
X254148Y-111532D01*
G01X264879Y-113865D02*
Y-102199D01*
G01Y-104532D02*
X265971Y-103365D01*
X267063Y-102490D01*
X268591Y-102199D01*
X269682Y-102490D01*
X270993Y-103365D01*
G01X298569Y-113865D02*
Y-96365D01*
X303809D01*
X305556Y-97240D01*
X306866Y-99282D01*
X307303Y-101615D01*
X306866Y-103948D01*
X305774Y-105698D01*
X303809Y-106574D01*
X298569D01*
G01X324366Y-113865D02*
Y-102199D01*
G01Y-104240D02*
X323493Y-103074D01*
X322182Y-102490D01*
X320654Y-102199D01*
X319126Y-102782D01*
X317816Y-103948D01*
X316942Y-105698D01*
X316506Y-108032D01*
X316942Y-110365D01*
X317816Y-112115D01*
X319126Y-113282D01*
X320654Y-113865D01*
X322182Y-113573D01*
X323493Y-112699D01*
X324366Y-111532D01*
G01X334224Y-113865D02*
Y-102199D01*
G01Y-105115D02*
X335098Y-103657D01*
X336408Y-102490D01*
X338154Y-102199D01*
X339682Y-102490D01*
X340993Y-103657D01*
X341648Y-105698D01*
Y-113865D01*
G01X355436Y-96365D02*
Y-113865D01*
G01X352379Y-102199D02*
X358493D01*
G01X369224Y-113865D02*
Y-96365D01*
G01Y-104823D02*
X370316Y-103365D01*
X371408Y-102490D01*
X373154Y-102199D01*
X374464Y-102490D01*
X375993Y-103657D01*
X376648Y-105407D01*
Y-113865D01*
G01X387161Y-105990D02*
X394148D01*
X393493Y-103948D01*
X392401Y-102782D01*
X390873Y-102199D01*
X389344Y-102490D01*
X388034Y-103365D01*
X387161Y-105407D01*
X386724Y-107157D01*
Y-108907D01*
X387161Y-110657D01*
X388253Y-112407D01*
X389563Y-113573D01*
X391091Y-113865D01*
X392619Y-113282D01*
X394148Y-111532D01*
G01X404879Y-113865D02*
Y-102199D01*
G01Y-104532D02*
X405971Y-103365D01*
X407063Y-102490D01*
X408591Y-102199D01*
X409682Y-102490D01*
X410993Y-103365D01*
G01X437259Y-113865D02*
Y-96365D01*
X442936Y-110948D01*
X448613Y-96365D01*
Y-113865D01*
G01X462182Y-104532D02*
X463056Y-103657D01*
X463711Y-102199D01*
X464148Y-100156D01*
X463711Y-98407D01*
X462838Y-97240D01*
X461309Y-96365D01*
X455414D01*
Y-113865D01*
X462619D01*
X464148Y-112699D01*
X465021Y-110948D01*
X465458Y-108907D01*
X465021Y-106865D01*
X463711Y-105115D01*
X462182Y-104532D01*
X455414D01*
G01X227259Y-68865D02*
Y-51365D01*
X232936Y-65948D01*
X238613Y-51365D01*
Y-68865D01*
G01X250436D02*
X249126Y-68573D01*
X247816Y-67407D01*
X246942Y-65365D01*
X246506Y-63032D01*
X246942Y-60698D01*
X247816Y-58657D01*
X249126Y-57490D01*
X250436Y-57199D01*
X251746Y-57490D01*
X253056Y-58657D01*
X253929Y-60698D01*
X254148Y-63032D01*
X253929Y-65365D01*
X253056Y-67407D01*
X251746Y-68573D01*
X250436Y-68865D01*
G01X271866Y-51365D02*
Y-68865D01*
G01Y-66241D02*
X270993Y-67699D01*
X269682Y-68573D01*
X268154Y-68865D01*
X266408Y-68282D01*
X265098Y-66824D01*
X264224Y-65074D01*
X264006Y-63032D01*
X264224Y-60990D01*
X265098Y-59240D01*
X266408Y-57782D01*
X268154Y-57199D01*
X269682Y-57490D01*
X270774Y-58074D01*
X271866Y-59240D01*
G01X282161Y-60990D02*
X289148D01*
X288493Y-58948D01*
X287401Y-57782D01*
X285873Y-57199D01*
X284344Y-57490D01*
X283034Y-58365D01*
X282161Y-60407D01*
X281724Y-62157D01*
Y-63907D01*
X282161Y-65657D01*
X283253Y-67407D01*
X284563Y-68573D01*
X286091Y-68865D01*
X287619Y-68282D01*
X289148Y-66532D01*
G01X302936Y-68865D02*
Y-51365D01*
G01X542319Y-68865D02*
Y-51365D01*
X547559D01*
X549306Y-52240D01*
X550616Y-54282D01*
X551053Y-56615D01*
X550616Y-58948D01*
X549524Y-60698D01*
X547559Y-61574D01*
X542319D01*
G01X568989Y-52824D02*
X567679Y-51948D01*
X566151Y-51365D01*
X564404D01*
X562439Y-52240D01*
X560911Y-53698D01*
X559819Y-55449D01*
X558946Y-58365D01*
X558727Y-60990D01*
X559164Y-63615D01*
X559819Y-65365D01*
X561129Y-67115D01*
X562658Y-68282D01*
X564186Y-68865D01*
X565714D01*
X567243Y-68282D01*
X568553Y-67407D01*
X569645Y-66241D01*
G01X583432Y-59532D02*
X584306Y-58657D01*
X584961Y-57199D01*
X585398Y-55156D01*
X584961Y-53407D01*
X584088Y-52240D01*
X582559Y-51365D01*
X576664D01*
Y-68865D01*
X583869D01*
X585398Y-67699D01*
X586271Y-65948D01*
X586708Y-63907D01*
X586271Y-61865D01*
X584961Y-60115D01*
X583432Y-59532D01*
X576664D01*
G01X592636Y-74698D02*
X605736D01*
G01X611664Y-68865D02*
Y-51365D01*
X621708Y-68865D01*
Y-51365D01*
G01X634186Y-68865D02*
X632439Y-68573D01*
X630911Y-67407D01*
X629601Y-65657D01*
X628727Y-63615D01*
X628291Y-61282D01*
Y-58948D01*
X628727Y-56615D01*
X629601Y-54573D01*
X630911Y-52824D01*
X632439Y-51657D01*
X634186Y-51365D01*
X635932Y-51657D01*
X637461Y-52824D01*
X638771Y-54573D01*
X639645Y-56615D01*
X640081Y-58948D01*
Y-61282D01*
X639645Y-63615D01*
X638771Y-65657D01*
X637461Y-67407D01*
X635932Y-68573D01*
X634186Y-68865D01*
G01X555436Y-113865D02*
Y-96365D01*
X552816Y-99865D01*
G01Y-113865D02*
X558056D01*
G01X568133Y-110365D02*
X569442Y-112407D01*
X571189Y-113573D01*
X573154Y-113865D01*
X574901Y-113573D01*
X576648Y-112115D01*
X577739Y-110365D01*
X577958Y-108615D01*
X577521Y-106574D01*
X575993Y-105115D01*
X574464Y-104532D01*
X572499D01*
G01X574464D02*
X575774Y-103657D01*
X576866Y-102199D01*
X577303Y-100449D01*
X576866Y-98698D01*
X575774Y-97240D01*
X573809Y-96365D01*
X571844Y-96657D01*
X569879Y-97824D01*
G01X590436Y-113865D02*
Y-96365D01*
X587816Y-99865D01*
G01Y-113865D02*
X593056D01*
G01X603133Y-110365D02*
X604442Y-112407D01*
X606189Y-113573D01*
X608154Y-113865D01*
X609901Y-113573D01*
X611648Y-112115D01*
X612739Y-110365D01*
X612958Y-108615D01*
X612521Y-106574D01*
X610993Y-105115D01*
X609464Y-104532D01*
X607499D01*
G01X609464D02*
X610774Y-103657D01*
X611866Y-102199D01*
X612303Y-100449D01*
X611866Y-98698D01*
X610774Y-97240D01*
X608809Y-96365D01*
X606844Y-96657D01*
X604879Y-97824D01*
G01X625436Y-96365D02*
X623689Y-96948D01*
X622379Y-98407D01*
X621506Y-100156D01*
X620851Y-102490D01*
X620633Y-105115D01*
X620851Y-107740D01*
X621506Y-110074D01*
X622379Y-111824D01*
X623689Y-113282D01*
X625436Y-113865D01*
X627182Y-113282D01*
X628493Y-111824D01*
X629366Y-110074D01*
X630021Y-107740D01*
X630239Y-105115D01*
X630021Y-102490D01*
X629366Y-100156D01*
X628493Y-98407D01*
X627182Y-96948D01*
X625436Y-96365D01*
G01X685027Y-51365D02*
X690486Y-68865D01*
X695945Y-51365D01*
G01X712353Y-68865D02*
X703619D01*
Y-51365D01*
X712353D01*
G01X708859Y-59823D02*
X703619D01*
G01X721119Y-68865D02*
Y-51365D01*
X726578D01*
X728324Y-52240D01*
X729416Y-53407D01*
X729853Y-55740D01*
X729416Y-58074D01*
X728106Y-59532D01*
X726578Y-60407D01*
X721119D01*
G01X726578D02*
X729853Y-68865D01*
G01X742986Y-69448D02*
X742549Y-69157D01*
Y-68573D01*
X742986Y-68282D01*
X743423Y-68573D01*
Y-69157D01*
X742986Y-69448D01*
G01X707986Y-113865D02*
Y-96365D01*
X705366Y-99865D01*
G01Y-113865D02*
X710606D01*
G01X727232Y-104532D02*
X728106Y-103657D01*
X728761Y-102199D01*
X729198Y-100156D01*
X728761Y-98407D01*
X727888Y-97240D01*
X726359Y-96365D01*
X720464D01*
Y-113865D01*
X727669D01*
X729198Y-112699D01*
X730071Y-110948D01*
X730508Y-108907D01*
X730071Y-106865D01*
X728761Y-105115D01*
X727232Y-104532D01*
X720464D01*
G01X818569Y-96365D02*
Y-113865D01*
X827303D01*
G01X836288Y-99282D02*
X837598Y-97532D01*
X839126Y-96657D01*
X840873Y-96365D01*
X843056Y-96948D01*
X844584Y-98407D01*
X845021Y-100156D01*
X844803Y-101907D01*
X843929Y-103365D01*
X839563Y-106282D01*
X837598Y-108323D01*
X836288Y-111241D01*
X835851Y-113865D01*
X845021D01*
G01X859246Y-105115D02*
X863613D01*
Y-110365D01*
X862303Y-112115D01*
X860774Y-113282D01*
X858591Y-113865D01*
X856408Y-113282D01*
X854879Y-112115D01*
X853569Y-110365D01*
X852696Y-108323D01*
X852259Y-105990D01*
Y-103948D01*
X852696Y-102199D01*
X853569Y-100156D01*
X854879Y-98407D01*
X856189Y-97240D01*
X857936Y-96365D01*
X859464D01*
X861211Y-96948D01*
X862521Y-98115D01*
G01X870414Y-113865D02*
Y-96365D01*
X880458Y-113865D01*
Y-96365D01*
G01X888133Y-113865D02*
Y-96365D01*
X892499D01*
X894246Y-97240D01*
X895556Y-98407D01*
X896648Y-100156D01*
X897521Y-102199D01*
X897739Y-105115D01*
X897521Y-108032D01*
X896648Y-110074D01*
X895556Y-111824D01*
X894246Y-112990D01*
X892499Y-113865D01*
X888133D01*
G01X818569Y-51365D02*
Y-68865D01*
X827303D01*
G01X844366D02*
Y-57199D01*
G01Y-59240D02*
X843493Y-58074D01*
X842182Y-57490D01*
X840654Y-57199D01*
X839126Y-57782D01*
X837816Y-58948D01*
X836942Y-60698D01*
X836506Y-63032D01*
X836942Y-65365D01*
X837816Y-67115D01*
X839126Y-68282D01*
X840654Y-68865D01*
X842182Y-68573D01*
X843493Y-67699D01*
X844366Y-66532D01*
G01X853351Y-74115D02*
X854661Y-74698D01*
X856408Y-74115D01*
X857499Y-72949D01*
X858373Y-71490D01*
X859682Y-66824D01*
X862521Y-57199D01*
G01X855534D02*
X859682Y-66824D01*
G01X872161Y-60990D02*
X879148D01*
X878493Y-58948D01*
X877401Y-57782D01*
X875873Y-57199D01*
X874344Y-57490D01*
X873034Y-58365D01*
X872161Y-60407D01*
X871724Y-62157D01*
Y-63907D01*
X872161Y-65657D01*
X873253Y-67407D01*
X874563Y-68573D01*
X876091Y-68865D01*
X877619Y-68282D01*
X879148Y-66532D01*
G01X889879Y-68865D02*
Y-57199D01*
G01Y-59532D02*
X890971Y-58365D01*
X892063Y-57490D01*
X893591Y-57199D01*
X894682Y-57490D01*
X895993Y-58365D01*
G01X943619Y-110365D02*
X944711Y-112115D01*
X946021Y-113282D01*
X947549Y-113865D01*
X949296Y-113282D01*
X950606Y-112115D01*
X951916Y-110365D01*
X952353Y-108032D01*
Y-96365D01*
G01X965486Y-113865D02*
X963739Y-113573D01*
X962211Y-112407D01*
X960901Y-110657D01*
X960027Y-108615D01*
X959591Y-106282D01*
Y-103948D01*
X960027Y-101615D01*
X960901Y-99573D01*
X962211Y-97824D01*
X963739Y-96657D01*
X965486Y-96365D01*
X967232Y-96657D01*
X968761Y-97824D01*
X970071Y-99573D01*
X970945Y-101615D01*
X971381Y-103948D01*
Y-106282D01*
X970945Y-108615D01*
X970071Y-110657D01*
X968761Y-112407D01*
X967232Y-113573D01*
X965486Y-113865D01*
G01X978401Y-111532D02*
X980148Y-112990D01*
X982113Y-113865D01*
X983859D01*
X985606Y-112990D01*
X986916Y-111532D01*
X987571Y-109490D01*
X987134Y-107449D01*
X986043Y-105698D01*
X984078Y-104532D01*
X981458Y-103948D01*
X979929Y-102782D01*
X979274Y-100740D01*
X979711Y-98698D01*
X980803Y-97240D01*
X982331Y-96365D01*
X983859D01*
X985388Y-96948D01*
X986698Y-98407D01*
G01X1004853Y-113865D02*
X996119D01*
Y-96365D01*
X1004853D01*
G01X1001359Y-104823D02*
X996119D01*
G01X1013619Y-113865D02*
Y-96365D01*
X1018859D01*
X1020606Y-97240D01*
X1021916Y-99282D01*
X1022353Y-101615D01*
X1021916Y-103948D01*
X1020824Y-105698D01*
X1018859Y-106574D01*
X1013619D01*
G01X1030901Y-113865D02*
Y-96365D01*
G01X1040071D02*
Y-113865D01*
G01Y-105115D02*
X1030901D01*
G01X1066119Y-96365D02*
Y-113865D01*
X1074853D01*
G01X1082527D02*
X1087986Y-96365D01*
X1093445Y-113865D01*
G01X1091479Y-107740D02*
X1084492D01*
G01X1100683Y-96365D02*
Y-108907D01*
X1101556Y-111532D01*
X1103303Y-113282D01*
X1105486Y-113865D01*
X1107669Y-113282D01*
X1109416Y-111532D01*
X1110289Y-108907D01*
Y-96365D01*
G01X960683Y-68865D02*
Y-51365D01*
X965049D01*
X966796Y-52240D01*
X968106Y-53407D01*
X969198Y-55156D01*
X970071Y-57199D01*
X970289Y-60115D01*
X970071Y-63032D01*
X969198Y-65074D01*
X968106Y-66824D01*
X966796Y-67990D01*
X965049Y-68865D01*
X960683D01*
G01X979711Y-60990D02*
X986698D01*
X986043Y-58948D01*
X984951Y-57782D01*
X983423Y-57199D01*
X981894Y-57490D01*
X980584Y-58365D01*
X979711Y-60407D01*
X979274Y-62157D01*
Y-63907D01*
X979711Y-65657D01*
X980803Y-67407D01*
X982113Y-68573D01*
X983641Y-68865D01*
X985169Y-68282D01*
X986698Y-66532D01*
G01X997211Y-66824D02*
X998303Y-67990D01*
X999831Y-68865D01*
X1001141D01*
X1002451Y-68282D01*
X1003324Y-67407D01*
X1003761Y-66241D01*
X1003543Y-64490D01*
X1002669Y-63615D01*
X998739Y-61865D01*
X997866Y-59823D01*
X998303Y-58365D01*
X999176Y-57490D01*
X1000486Y-57199D01*
X1001796Y-57490D01*
X1003106Y-58365D01*
G01X1017986Y-57199D02*
Y-68865D01*
G01Y-52532D02*
X1017549Y-52240D01*
Y-51657D01*
X1017986Y-51365D01*
X1018423Y-51657D01*
Y-52240D01*
X1017986Y-52532D01*
G01X1032429Y-73240D02*
X1033958Y-74407D01*
X1035704Y-74698D01*
X1037232Y-74407D01*
X1038543Y-72949D01*
X1039416Y-70907D01*
Y-57199D01*
G01Y-59532D02*
X1038543Y-58365D01*
X1037232Y-57490D01*
X1035704Y-57199D01*
X1033958Y-57782D01*
X1032866Y-58948D01*
X1031992Y-60990D01*
X1031556Y-63032D01*
X1031774Y-64782D01*
X1032648Y-66824D01*
X1033958Y-68282D01*
X1035704Y-68865D01*
X1037014Y-68573D01*
X1038543Y-67407D01*
X1039416Y-66241D01*
G01X1049274Y-68865D02*
Y-57199D01*
G01Y-60115D02*
X1050148Y-58657D01*
X1051458Y-57490D01*
X1053204Y-57199D01*
X1054732Y-57490D01*
X1056043Y-58657D01*
X1056698Y-60698D01*
Y-68865D01*
G01X1067211Y-60990D02*
X1074198D01*
X1073543Y-58948D01*
X1072451Y-57782D01*
X1070923Y-57199D01*
X1069394Y-57490D01*
X1068084Y-58365D01*
X1067211Y-60407D01*
X1066774Y-62157D01*
Y-63907D01*
X1067211Y-65657D01*
X1068303Y-67407D01*
X1069613Y-68573D01*
X1071141Y-68865D01*
X1072669Y-68282D01*
X1074198Y-66532D01*
G01X1084929Y-68865D02*
Y-57199D01*
G01Y-59532D02*
X1086021Y-58365D01*
X1087113Y-57490D01*
X1088641Y-57199D01*
X1089732Y-57490D01*
X1091043Y-58365D01*
G01X1131686Y-113865D02*
Y-96365D01*
X1129066Y-99865D01*
G01Y-113865D02*
X1134306D01*
G01X1149186D02*
Y-96365D01*
X1146566Y-99865D01*
G01Y-113865D02*
X1151806D01*
G01X1162756Y-114448D02*
X1170616Y-96365D01*
G01X1184186Y-113865D02*
Y-96365D01*
X1181566Y-99865D01*
G01Y-113865D02*
X1186806D01*
G01X1196883Y-110365D02*
X1198192Y-112407D01*
X1199939Y-113573D01*
X1201904Y-113865D01*
X1203651Y-113573D01*
X1205398Y-112115D01*
X1206489Y-110365D01*
X1206708Y-108615D01*
X1206271Y-106574D01*
X1204743Y-105115D01*
X1203214Y-104532D01*
X1201249D01*
G01X1203214D02*
X1204524Y-103657D01*
X1205616Y-102199D01*
X1206053Y-100449D01*
X1205616Y-98698D01*
X1204524Y-97240D01*
X1202559Y-96365D01*
X1200594Y-96657D01*
X1198629Y-97824D01*
G01X1215256Y-114448D02*
X1223116Y-96365D01*
G01X1232538Y-99282D02*
X1233848Y-97532D01*
X1235376Y-96657D01*
X1237123Y-96365D01*
X1239306Y-96948D01*
X1240834Y-98407D01*
X1241271Y-100156D01*
X1241053Y-101907D01*
X1240179Y-103365D01*
X1235813Y-106282D01*
X1233848Y-108323D01*
X1232538Y-111241D01*
X1232101Y-113865D01*
X1241271D01*
G01X1254186Y-96365D02*
X1252439Y-96948D01*
X1251129Y-98407D01*
X1250256Y-100156D01*
X1249601Y-102490D01*
X1249383Y-105115D01*
X1249601Y-107740D01*
X1250256Y-110074D01*
X1251129Y-111824D01*
X1252439Y-113282D01*
X1254186Y-113865D01*
X1255932Y-113282D01*
X1257243Y-111824D01*
X1258116Y-110074D01*
X1258771Y-107740D01*
X1258989Y-105115D01*
X1258771Y-102490D01*
X1258116Y-100156D01*
X1257243Y-98407D01*
X1255932Y-96948D01*
X1254186Y-96365D01*
G01X1271686Y-113865D02*
Y-96365D01*
X1269066Y-99865D01*
G01Y-113865D02*
X1274306D01*
G01X1291806D02*
Y-96365D01*
X1283727Y-108907D01*
X1294645D01*
G01X1179383Y-68865D02*
Y-51365D01*
X1183749D01*
X1185496Y-52240D01*
X1186806Y-53407D01*
X1187898Y-55156D01*
X1188771Y-57199D01*
X1188989Y-60115D01*
X1188771Y-63032D01*
X1187898Y-65074D01*
X1186806Y-66824D01*
X1185496Y-67990D01*
X1183749Y-68865D01*
X1179383D01*
G01X1205616D02*
Y-57199D01*
G01Y-59240D02*
X1204743Y-58074D01*
X1203432Y-57490D01*
X1201904Y-57199D01*
X1200376Y-57782D01*
X1199066Y-58948D01*
X1198192Y-60698D01*
X1197756Y-63032D01*
X1198192Y-65365D01*
X1199066Y-67115D01*
X1200376Y-68282D01*
X1201904Y-68865D01*
X1203432Y-68573D01*
X1204743Y-67699D01*
X1205616Y-66532D01*
G01X1219186Y-51365D02*
Y-68865D01*
G01X1216129Y-57199D02*
X1222243D01*
G01X1233411Y-60990D02*
X1240398D01*
X1239743Y-58948D01*
X1238651Y-57782D01*
X1237123Y-57199D01*
X1235594Y-57490D01*
X1234284Y-58365D01*
X1233411Y-60407D01*
X1232974Y-62157D01*
Y-63907D01*
X1233411Y-65657D01*
X1234503Y-67407D01*
X1235813Y-68573D01*
X1237341Y-68865D01*
X1238869Y-68282D01*
X1240398Y-66532D01*
M02*
